FILE_TYPE = MACRO_DRAWING;
SET COLOR_WIRE YELLOW;
SET COLOR_PROP ORANGE;
SET COLOR_DOT WHITE;
SET COLOR_ARC YELLOW;
SET COLOR_BODY GREEN;
SET COLOR_NOTE PURPLE;
SET PROP_DISPLAY VALUE;
SET PAGE_NUMBER P178;
FORCEADD Q_CAP..1
(5775 2800);
FORCEPROP 1 LAST LOCATION PC119_6
J 0
(5825 2950);
DISPLAY 0.489362 (5825 2950);
PAINT SKYBLUE (5825 2950);
FORCEPROP 0 LAST $SEC 1
J 0
(5825 3000);
DISPLAY 0.680851 (5825 3000);
PAINT MONO (5825 3000);
DISPLAY INVISIBLE (5825 3000);
FORCEPROP 0 LAST CDS_SEC 1
J 0
(5825 3000);
DISPLAY 1.021277 (5825 3000);
DISPLAY INVISIBLE (5825 3000);
FORCEPROP 1 LASTPIN (5775 2900) $PN 1
J 0
(5785 2880);
DISPLAY 0.489362 (5785 2880);
PAINT MONO (5785 2880);
FORCEPROP 1 LASTPIN (5775 2700) $PN 2
J 0
(5785 2680);
DISPLAY 0.489362 (5785 2680);
PAINT MONO (5785 2680);
FORCEPROP 1 LAST TOLERANCE 10%
J 0
(5825 2800);
DISPLAY 0.489362 (5825 2800);
PAINT SKYBLUE (5825 2800);
FORCEPROP 1 LAST VOLTAGE 25V
J 0
(5825 2850);
DISPLAY 0.489362 (5825 2850);
PAINT SKYBLUE (5825 2850);
FORCEPROP 1 LAST VALUE 10UF
J 0
(5825 2900);
DISPLAY 0.489362 (5825 2900);
PAINT SKYBLUE (5825 2900);
FORCEPROP 1 LAST MATERIAL X6S
J 0
(5825 2750);
DISPLAY 0.489362 (5825 2750);
PAINT SKYBLUE (5825 2750);
FORCEPROP 1 LAST PART_NUMBER CH6104KEA00
J 0
(5825 2650);
DISPLAY 0.489362 (5825 2650);
PAINT SKYBLUE (5825 2650);
FORCEPROP 1 LAST PACK_TYPE C0805
J 0
(5825 2700);
DISPLAY 0.489362 (5825 2700);
PAINT SKYBLUE (5825 2700);
FORCEPROP 2 LAST CDS_LIB pure_quanta
J 0
(5775 2800);
DISPLAY INVISIBLE (5775 2800);
FORCEPROP 1 LAST PATH I100
J 0
(5825 2950);
DISPLAY 0.978723 (5825 2950);
PAINT WHITE (5825 2950);
DISPLAY INVISIBLE (5825 2950);
FORCEADD Q_CAP..1
(5400 2800);
FORCEPROP 1 LAST LOCATION PC118_6
J 0
(5450 2950);
DISPLAY 0.489362 (5450 2950);
PAINT SKYBLUE (5450 2950);
FORCEPROP 0 LAST $SEC 1
J 0
(5450 3000);
DISPLAY 0.680851 (5450 3000);
PAINT MONO (5450 3000);
DISPLAY INVISIBLE (5450 3000);
FORCEPROP 0 LAST CDS_SEC 1
J 0
(5450 3000);
DISPLAY 1.021277 (5450 3000);
DISPLAY INVISIBLE (5450 3000);
FORCEPROP 1 LASTPIN (5400 2900) $PN 1
J 0
(5410 2880);
DISPLAY 0.489362 (5410 2880);
PAINT MONO (5410 2880);
FORCEPROP 1 LASTPIN (5400 2700) $PN 2
J 0
(5410 2680);
DISPLAY 0.489362 (5410 2680);
PAINT MONO (5410 2680);
FORCEPROP 1 LAST PART_NUMBER CH6104KEA00
J 0
(5450 2650);
DISPLAY 0.489362 (5450 2650);
PAINT SKYBLUE (5450 2650);
FORCEPROP 1 LAST MATERIAL X6S
J 0
(5450 2750);
DISPLAY 0.489362 (5450 2750);
PAINT SKYBLUE (5450 2750);
FORCEPROP 1 LAST TOLERANCE 10%
J 0
(5450 2800);
DISPLAY 0.489362 (5450 2800);
PAINT SKYBLUE (5450 2800);
FORCEPROP 1 LAST VALUE 10UF
J 0
(5450 2900);
DISPLAY 0.489362 (5450 2900);
PAINT SKYBLUE (5450 2900);
FORCEPROP 1 LAST VOLTAGE 25V
J 0
(5450 2850);
DISPLAY 0.489362 (5450 2850);
PAINT SKYBLUE (5450 2850);
FORCEPROP 1 LAST PACK_TYPE C0805
J 0
(5450 2700);
DISPLAY 0.489362 (5450 2700);
PAINT SKYBLUE (5450 2700);
FORCEPROP 2 LAST CDS_LIB pure_quanta
J 0
(5400 2800);
DISPLAY INVISIBLE (5400 2800);
FORCEPROP 1 LAST PATH I101
J 0
(5450 2950);
DISPLAY 0.978723 (5450 2950);
PAINT WHITE (5450 2950);
DISPLAY INVISIBLE (5450 2950);
FORCEADD UNIVERSAL_GND..1
(5775 2450);
FORCEPROP 3 LASTPIN (5775 2500) SIG_NAME GND\g
J 0
(5785 2510);
DISPLAY 0.659574 (5785 2510);
PAINT MONO (5785 2510);
DISPLAY INVISIBLE (5785 2510);
FORCEPROP 2 LAST CDS_LIB pure_quanta_power
J 0
(5775 2450);
PAINT MONO (5775 2450);
DISPLAY INVISIBLE (5775 2450);
FORCEPROP 1 LAST PATH I102
J 0
(5850 2450);
DISPLAY 0.872340 (5850 2450);
PAINT AQUA (5850 2450);
DISPLAY INVISIBLE (5850 2450);
FORCEPROP 1 LAST HDL_POWER GND
J 1
(5800 2375);
DISPLAY 0.872340 (5800 2375);
PAINT GREEN (5800 2375);
DISPLAY INVISIBLE (5800 2375);
FORCEADD Q_CAP..1
(5300 2125);
FORCEPROP 1 LAST LOCATION PC117
J 0
(5350 2225);
DISPLAY 0.489362 (5350 2225);
PAINT SKYBLUE (5350 2225);
FORCEPROP 0 LAST $SEC 1
J 0
(5350 2275);
DISPLAY 0.680851 (5350 2275);
PAINT MONO (5350 2275);
DISPLAY INVISIBLE (5350 2275);
FORCEPROP 0 LAST CDS_SEC 1
J 2
(5350 2250);
DISPLAY 1.021277 (5350 2250);
DISPLAY INVISIBLE (5350 2250);
FORCEPROP 1 LASTPIN (5300 2225) $PN 1
J 0
(5310 2205);
DISPLAY 0.489362 (5310 2205);
PAINT MONO (5310 2205);
FORCEPROP 1 LASTPIN (5300 2025) $PN 2
J 0
(5310 2005);
DISPLAY 0.489362 (5310 2005);
PAINT MONO (5310 2005);
FORCEPROP 1 LAST PART_NUMBER CH4223K1B00
J 0
(5350 1975);
DISPLAY 0.489362 (5350 1975);
PAINT SKYBLUE (5350 1975);
FORCEPROP 1 LAST VALUE 0.22UF
J 0
(5350 2175);
DISPLAY 0.489362 (5350 2175);
PAINT SKYBLUE (5350 2175);
FORCEPROP 1 LAST VOLTAGE 16V
J 0
(5350 2125);
DISPLAY 0.489362 (5350 2125);
PAINT SKYBLUE (5350 2125);
FORCEPROP 1 LAST TOLERANCE 10%
J 0
(5350 2075);
DISPLAY 0.489362 (5350 2075);
PAINT SKYBLUE (5350 2075);
FORCEPROP 1 LAST MATERIAL X7R
J 0
(5350 2025);
DISPLAY 0.489362 (5350 2025);
PAINT SKYBLUE (5350 2025);
FORCEPROP 1 LAST PACK_TYPE 0402
J 0
(5350 1925);
DISPLAY 0.489362 (5350 1925);
PAINT SKYBLUE (5350 1925);
FORCEPROP 2 LAST CDS_LIB pure_quanta
J 2
(5300 2125);
DISPLAY INVISIBLE (5300 2125);
FORCEPROP 1 LAST PATH I103
J 0
(5350 2275);
DISPLAY 0.978723 (5350 2275);
PAINT WHITE (5350 2275);
DISPLAY INVISIBLE (5350 2275);
FORCEADD Q_CAP..1
(5000 2800);
FORCEPROP 1 LAST LOCATION PC116_6
J 0
(5050 2950);
DISPLAY 0.489362 (5050 2950);
PAINT SKYBLUE (5050 2950);
FORCEPROP 0 LAST $SEC 1
J 0
(5050 3000);
DISPLAY 0.680851 (5050 3000);
PAINT MONO (5050 3000);
DISPLAY INVISIBLE (5050 3000);
FORCEPROP 0 LAST CDS_SEC 1
J 0
(5050 3000);
DISPLAY 1.021277 (5050 3000);
DISPLAY INVISIBLE (5050 3000);
FORCEPROP 1 LASTPIN (5000 2900) $PN 1
J 0
(5010 2880);
DISPLAY 0.489362 (5010 2880);
PAINT MONO (5010 2880);
FORCEPROP 1 LASTPIN (5000 2700) $PN 2
J 0
(5010 2680);
DISPLAY 0.489362 (5010 2680);
PAINT MONO (5010 2680);
FORCEPROP 1 LAST PACK_TYPE C0805
J 0
(5050 2700);
DISPLAY 0.489362 (5050 2700);
PAINT SKYBLUE (5050 2700);
FORCEPROP 1 LAST PART_NUMBER CH6104KEA00
J 0
(5050 2650);
DISPLAY 0.489362 (5050 2650);
PAINT SKYBLUE (5050 2650);
FORCEPROP 1 LAST MATERIAL X6S
J 0
(5050 2750);
DISPLAY 0.489362 (5050 2750);
PAINT SKYBLUE (5050 2750);
FORCEPROP 1 LAST TOLERANCE 10%
J 0
(5050 2800);
DISPLAY 0.489362 (5050 2800);
PAINT SKYBLUE (5050 2800);
FORCEPROP 1 LAST VALUE 10UF
J 0
(5050 2900);
DISPLAY 0.489362 (5050 2900);
PAINT SKYBLUE (5050 2900);
FORCEPROP 1 LAST VOLTAGE 25V
J 0
(5050 2850);
DISPLAY 0.489362 (5050 2850);
PAINT SKYBLUE (5050 2850);
FORCEPROP 2 LAST CDS_LIB pure_quanta
J 0
(5000 2800);
DISPLAY INVISIBLE (5000 2800);
FORCEPROP 1 LAST PATH I105
J 0
(5050 2950);
DISPLAY 0.978723 (5050 2950);
PAINT WHITE (5050 2950);
DISPLAY INVISIBLE (5050 2950);
FORCEADD Q_CAP..1
(4600 2800);
FORCEPROP 1 LAST LOCATION PC115_6
J 0
(4650 2950);
DISPLAY 0.489362 (4650 2950);
PAINT SKYBLUE (4650 2950);
FORCEPROP 0 LAST $SEC 1
J 0
(4650 3000);
DISPLAY 0.680851 (4650 3000);
PAINT MONO (4650 3000);
DISPLAY INVISIBLE (4650 3000);
FORCEPROP 0 LAST CDS_SEC 1
J 0
(4650 3000);
DISPLAY 1.021277 (4650 3000);
DISPLAY INVISIBLE (4650 3000);
FORCEPROP 1 LASTPIN (4600 2900) $PN 1
J 0
(4610 2880);
DISPLAY 0.489362 (4610 2880);
PAINT MONO (4610 2880);
FORCEPROP 1 LASTPIN (4600 2700) $PN 2
J 0
(4610 2680);
DISPLAY 0.489362 (4610 2680);
PAINT MONO (4610 2680);
FORCEPROP 1 LAST MATERIAL X6S
J 0
(4650 2750);
DISPLAY 0.489362 (4650 2750);
PAINT SKYBLUE (4650 2750);
FORCEPROP 1 LAST TOLERANCE 10%
J 0
(4650 2800);
DISPLAY 0.489362 (4650 2800);
PAINT SKYBLUE (4650 2800);
FORCEPROP 1 LAST VALUE 1UF
J 0
(4650 2900);
DISPLAY 0.489362 (4650 2900);
PAINT SKYBLUE (4650 2900);
FORCEPROP 1 LAST PART_NUMBER CH5104KEB02
J 0
(4650 2650);
DISPLAY 0.489362 (4650 2650);
PAINT SKYBLUE (4650 2650);
FORCEPROP 1 LAST VOLTAGE 25V
J 0
(4650 2850);
DISPLAY 0.489362 (4650 2850);
PAINT SKYBLUE (4650 2850);
FORCEPROP 1 LAST PACK_TYPE C0402
J 0
(4650 2700);
DISPLAY 0.489362 (4650 2700);
PAINT SKYBLUE (4650 2700);
FORCEPROP 2 LAST CDS_LIB pure_quanta
J 0
(4600 2800);
DISPLAY INVISIBLE (4600 2800);
FORCEPROP 1 LAST PATH I106
J 0
(4650 2950);
DISPLAY 0.978723 (4650 2950);
PAINT WHITE (4650 2950);
DISPLAY INVISIBLE (4650 2950);
FORCEADD Q_CAP..1
(4175 2800);
FORCEPROP 1 LAST LOCATION PC114_6
J 0
(4225 2950);
DISPLAY 0.489362 (4225 2950);
PAINT SKYBLUE (4225 2950);
FORCEPROP 0 LAST $SEC 1
J 0
(4225 2950);
DISPLAY 0.680851 (4225 2950);
PAINT MONO (4225 2950);
DISPLAY INVISIBLE (4225 2950);
FORCEPROP 0 LAST CDS_SEC 1
J 0
(4225 2950);
DISPLAY 1.021277 (4225 2950);
DISPLAY INVISIBLE (4225 2950);
FORCEPROP 1 LASTPIN (4175 2900) $PN 1
J 0
(4185 2880);
DISPLAY 0.489362 (4185 2880);
PAINT MONO (4185 2880);
FORCEPROP 1 LASTPIN (4175 2700) $PN 2
J 0
(4185 2680);
DISPLAY 0.489362 (4185 2680);
PAINT MONO (4185 2680);
FORCEPROP 1 LAST MATERIAL X7R
J 0
(4225 2750);
DISPLAY 0.489362 (4225 2750);
PAINT SKYBLUE (4225 2750);
FORCEPROP 1 LAST TOLERANCE 10%
J 0
(4225 2800);
DISPLAY 0.489362 (4225 2800);
PAINT SKYBLUE (4225 2800);
FORCEPROP 1 LAST VALUE 0.1UF
J 0
(4225 2900);
DISPLAY 0.489362 (4225 2900);
PAINT SKYBLUE (4225 2900);
FORCEPROP 1 LAST PART_NUMBER CH4104K1B00
J 0
(4225 2700);
DISPLAY 0.489362 (4225 2700);
PAINT SKYBLUE (4225 2700);
FORCEPROP 1 LAST VOLTAGE 25V
J 0
(4225 2850);
DISPLAY 0.489362 (4225 2850);
PAINT SKYBLUE (4225 2850);
FORCEPROP 1 LAST PACK_TYPE 0402
J 0
(4225 2650);
DISPLAY 0.489362 (4225 2650);
PAINT SKYBLUE (4225 2650);
FORCEPROP 2 LAST CDS_LIB pure_quanta
J 0
(4175 2800);
DISPLAY INVISIBLE (4175 2800);
FORCEPROP 1 LAST PATH I107
J 0
(4225 2950);
DISPLAY 0.978723 (4225 2950);
PAINT WHITE (4225 2950);
DISPLAY INVISIBLE (4225 2950);
FORCEADD Q_RES..1
(4575 2250);
FORCEPROP 1 LAST LOCATION PR420
J 0
(4350 2325);
DISPLAY 0.489362 (4350 2325);
PAINT SKYBLUE (4350 2325);
FORCEPROP 0 LAST $SEC 1
J 0
(4850 2350);
DISPLAY 0.680851 (4850 2350);
PAINT MONO (4850 2350);
DISPLAY INVISIBLE (4850 2350);
FORCEPROP 0 LAST CDS_SEC 1
J 0
(4850 2350);
DISPLAY 1.021277 (4850 2350);
DISPLAY INVISIBLE (4850 2350);
FORCEPROP 1 LASTPIN (4475 2250) $PN 1
J 0
(4487 2262);
DISPLAY 0.787234 (4487 2262);
PAINT MONO (4487 2262);
DISPLAY INVISIBLE (4487 2262);
FORCEPROP 1 LASTPIN (4675 2250) $PN 2
J 0
(4637 2262);
DISPLAY 0.787234 (4637 2262);
PAINT MONO (4637 2262);
DISPLAY INVISIBLE (4637 2262);
FORCEPROP 1 LAST TOLERANCE 1%
J 0
(4575 2325);
DISPLAY 0.489362 (4575 2325);
PAINT SKYBLUE (4575 2325);
FORCEPROP 1 LAST MATERIAL CHIP
J 0
(4425 2175);
DISPLAY 0.489362 (4425 2175);
PAINT SKYBLUE (4425 2175);
FORCEPROP 1 LAST PACK_TYPE 0402LF
J 0
(4975 2175);
DISPLAY 0.489362 (4975 2175);
PAINT SKYBLUE (4975 2175);
FORCEPROP 1 LAST WATTAGE 1/16W
J 2
(4850 2325);
DISPLAY 0.489362 (4850 2325);
PAINT SKYBLUE (4850 2325);
FORCEPROP 1 LAST VALUE 4.7
J 2
(4525 2325);
DISPLAY 0.489362 (4525 2325);
PAINT SKYBLUE (4525 2325);
FORCEPROP 1 LAST PART_NUMBER CS-4702FB19
J 0
(4600 2175);
DISPLAY 0.489362 (4600 2175);
PAINT SKYBLUE (4600 2175);
FORCEPROP 1 LAST PATH I108
J 0
(4525 2400);
DISPLAY 0.978723 (4525 2400);
PAINT WHITE (4525 2400);
DISPLAY INVISIBLE (4525 2400);
FORCEPROP 2 LAST CDS_LIB pure_quanta
J 0
(4575 2250);
DISPLAY INVISIBLE (4575 2250);
FORCEADD UNIVERSAL_GND..1
(8050 1350);
FORCEPROP 3 LASTPIN (8050 1400) SIG_NAME GND\g
J 0
(8060 1410);
DISPLAY 0.659574 (8060 1410);
PAINT MONO (8060 1410);
DISPLAY INVISIBLE (8060 1410);
FORCEPROP 2 LAST CDS_LIB pure_quanta_power
J 0
(8050 1350);
PAINT MONO (8050 1350);
DISPLAY INVISIBLE (8050 1350);
FORCEPROP 1 LAST PATH I109
J 0
(8125 1350);
DISPLAY 0.872340 (8125 1350);
PAINT AQUA (8125 1350);
DISPLAY INVISIBLE (8125 1350);
FORCEPROP 1 LAST HDL_POWER GND
J 1
(8075 1275);
DISPLAY 0.872340 (8075 1275);
PAINT GREEN (8075 1275);
DISPLAY INVISIBLE (8075 1275);
FORCEADD Q_RES..1
(5925 775);
FORCEPROP 1 LAST LOCATION PR421
J 0
(5875 800);
DISPLAY 0.489362 (5875 800);
PAINT SKYBLUE (5875 800);
FORCEPROP 0 LAST $SEC 1
J 0
(6175 925);
DISPLAY 0.680851 (6175 925);
PAINT MONO (6175 925);
DISPLAY INVISIBLE (6175 925);
FORCEPROP 0 LAST CDS_SEC 1
J 0
(6175 925);
DISPLAY 1.021277 (6175 925);
DISPLAY INVISIBLE (6175 925);
FORCEPROP 1 LASTPIN (5825 775) $PN 1
J 0
(5837 787);
DISPLAY 0.489362 (5837 787);
PAINT MONO (5837 787);
FORCEPROP 1 LASTPIN (6025 775) $PN 2
J 0
(5987 787);
DISPLAY 0.489362 (5987 787);
PAINT MONO (5987 787);
FORCEPROP 1 LAST PART_NUMBER CS00002JB38
J 0
(5625 725);
DISPLAY 0.489362 (5625 725);
PAINT SKYBLUE (5625 725);
FORCEPROP 1 LAST WATTAGE 1/16W
J 2
(6175 850);
DISPLAY 0.489362 (6175 850);
PAINT SKYBLUE (6175 850);
FORCEPROP 1 LAST MATERIAL CHIP
J 0
(6075 800);
DISPLAY 0.489362 (6075 800);
PAINT SKYBLUE (6075 800);
FORCEPROP 1 LAST TOLERANCE 5%
J 0
(5750 800);
DISPLAY 0.489362 (5750 800);
PAINT SKYBLUE (5750 800);
FORCEPROP 1 LAST VALUE 0
J 2
(5725 800);
DISPLAY 0.489362 (5725 800);
PAINT SKYBLUE (5725 800);
FORCEPROP 1 LAST PACK_TYPE 0402LF
J 0
(6050 725);
DISPLAY 0.489362 (6050 725);
PAINT SKYBLUE (6050 725);
FORCEPROP 2 LAST CDS_LIB pure_quanta
J 0
(5925 775);
DISPLAY INVISIBLE (5925 775);
FORCEPROP 1 LAST PATH I110
J 0
(5875 925);
DISPLAY 0.978723 (5875 925);
PAINT WHITE (5875 925);
DISPLAY INVISIBLE (5875 925);
FORCEADD Q_CAP..1
(2200 2900);
FORCEPROP 1 LAST LOCATION PC113_C1P0_6
J 0
(2250 3000);
DISPLAY 0.489362 (2250 3000);
PAINT SKYBLUE (2250 3000);
FORCEPROP 0 LAST $SEC 1
J 0
(2250 3050);
DISPLAY 0.680851 (2250 3050);
PAINT MONO (2250 3050);
DISPLAY INVISIBLE (2250 3050);
FORCEPROP 0 LAST CDS_SEC 1
J 0
(2250 3050);
DISPLAY 1.021277 (2250 3050);
DISPLAY INVISIBLE (2250 3050);
FORCEPROP 1 LASTPIN (2200 3000) $PN 1
J 0
(2210 2980);
DISPLAY 0.489362 (2210 2980);
PAINT MONO (2210 2980);
FORCEPROP 1 LASTPIN (2200 2800) $PN 2
J 0
(2210 2780);
DISPLAY 0.489362 (2210 2780);
PAINT MONO (2210 2780);
FORCEPROP 1 LAST MATERIAL X6S
J 0
(2250 2800);
DISPLAY 0.489362 (2250 2800);
PAINT SKYBLUE (2250 2800);
FORCEPROP 1 LAST TOLERANCE 10%
J 0
(2250 2850);
DISPLAY 0.489362 (2250 2850);
PAINT SKYBLUE (2250 2850);
FORCEPROP 1 LAST VALUE 2.2UF
J 0
(2250 2950);
DISPLAY 0.489362 (2250 2950);
PAINT SKYBLUE (2250 2950);
FORCEPROP 1 LAST PART_NUMBER CH5222KEB01
J 0
(2250 2750);
DISPLAY 0.489362 (2250 2750);
PAINT SKYBLUE (2250 2750);
FORCEPROP 1 LAST VOLTAGE 10V
J 0
(2250 2900);
DISPLAY 0.489362 (2250 2900);
PAINT SKYBLUE (2250 2900);
FORCEPROP 1 LAST PACK_TYPE C0402
J 0
(2250 2700);
DISPLAY 0.489362 (2250 2700);
PAINT SKYBLUE (2250 2700);
FORCEPROP 2 LAST CDS_LIB pure_quanta
J 0
(2200 2900);
DISPLAY INVISIBLE (2200 2900);
FORCEPROP 1 LAST PATH I111
J 0
(2250 3050);
DISPLAY 0.978723 (2250 3050);
PAINT WHITE (2250 3050);
DISPLAY INVISIBLE (2250 3050);
FORCEADD UNIVERSAL_GND..1
(2200 2625);
FORCEPROP 3 LASTPIN (2200 2675) SIG_NAME GND\g
J 0
(2210 2685);
DISPLAY 0.659574 (2210 2685);
PAINT MONO (2210 2685);
DISPLAY INVISIBLE (2210 2685);
FORCEPROP 2 LAST CDS_LIB pure_quanta_power
J 0
(2200 2625);
DISPLAY INVISIBLE (2200 2625);
FORCEPROP 1 LAST PATH I112
J 0
(2275 2625);
DISPLAY 0.872340 (2275 2625);
PAINT AQUA (2275 2625);
DISPLAY INVISIBLE (2275 2625);
FORCEPROP 1 LAST HDL_POWER GND
J 1
(2225 2550);
DISPLAY 0.872340 (2225 2550);
PAINT GREEN (2225 2550);
DISPLAY INVISIBLE (2225 2550);
FORCEADD Q_RES..2
(1850 2875);
FORCEPROP 1 LAST LOCATION PR416
J 0
(1895 3000);
DISPLAY 0.489362 (1895 3000);
PAINT SKYBLUE (1895 3000);
FORCEPROP 0 LAST $SEC 1
J 0
(1900 3050);
DISPLAY 0.680851 (1900 3050);
PAINT MONO (1900 3050);
DISPLAY INVISIBLE (1900 3050);
FORCEPROP 0 LAST CDS_SEC 1
J 0
(1900 3050);
DISPLAY 1.021277 (1900 3050);
DISPLAY INVISIBLE (1900 3050);
FORCEPROP 1 LASTPIN (1850 2975) $PN 1
J 0
(1855 2937);
DISPLAY 0.489362 (1855 2937);
PAINT MONO (1855 2937);
FORCEPROP 1 LASTPIN (1850 2775) $PN 2
J 0
(1855 2785);
DISPLAY 0.489362 (1855 2785);
PAINT MONO (1855 2785);
FORCEPROP 1 LAST WATTAGE 1/16W
J 0
(1900 2850);
DISPLAY 0.489362 (1900 2850);
PAINT SKYBLUE (1900 2850);
FORCEPROP 1 LAST MATERIAL CHIP
J 0
(1900 2800);
DISPLAY 0.489362 (1900 2800);
PAINT SKYBLUE (1900 2800);
FORCEPROP 1 LAST TOLERANCE 1%
J 0
(1900 2900);
DISPLAY 0.489362 (1900 2900);
PAINT SKYBLUE (1900 2900);
FORCEPROP 1 LAST VALUE 2.2
J 0
(1900 2950);
DISPLAY 0.489362 (1900 2950);
PAINT SKYBLUE (1900 2950);
FORCEPROP 1 LAST PART_NUMBER CS-2202FB00
J 0
(1900 2750);
DISPLAY 0.489362 (1900 2750);
PAINT SKYBLUE (1900 2750);
FORCEPROP 1 LAST PACK_TYPE 0402LF
J 0
(1900 2700);
DISPLAY 0.489362 (1900 2700);
PAINT SKYBLUE (1900 2700);
FORCEPROP 2 LAST CDS_LIB pure_quanta
J 0
(1850 2875);
DISPLAY INVISIBLE (1850 2875);
FORCEPROP 1 LAST PATH I114
J 0
(1900 3050);
DISPLAY 0.978723 (1900 3050);
PAINT WHITE (1900 3050);
DISPLAY INVISIBLE (1900 3050);
FORCEADD Q_CAP..1
(1850 2325);
FORCEPROP 1 LAST LOCATION PC112
J 0
(1900 2425);
DISPLAY 0.489362 (1900 2425);
PAINT SKYBLUE (1900 2425);
FORCEPROP 0 LAST $SEC 1
J 0
(1900 2475);
DISPLAY 0.680851 (1900 2475);
PAINT MONO (1900 2475);
DISPLAY INVISIBLE (1900 2475);
FORCEPROP 0 LAST CDS_SEC 1
J 0
(1900 2475);
DISPLAY 1.021277 (1900 2475);
DISPLAY INVISIBLE (1900 2475);
FORCEPROP 1 LASTPIN (1850 2425) $PN 1
J 0
(1860 2405);
DISPLAY 0.489362 (1860 2405);
PAINT MONO (1860 2405);
FORCEPROP 1 LASTPIN (1850 2225) $PN 2
J 0
(1860 2205);
DISPLAY 0.489362 (1860 2205);
PAINT MONO (1860 2205);
FORCEPROP 1 LAST MATERIAL X6S
J 0
(1900 2225);
DISPLAY 0.489362 (1900 2225);
PAINT SKYBLUE (1900 2225);
FORCEPROP 1 LAST TOLERANCE 10%
J 0
(1900 2275);
DISPLAY 0.489362 (1900 2275);
PAINT SKYBLUE (1900 2275);
FORCEPROP 1 LAST VALUE 2.2UF
J 0
(1900 2375);
DISPLAY 0.489362 (1900 2375);
PAINT SKYBLUE (1900 2375);
FORCEPROP 1 LAST PART_NUMBER CH5222KEB01
J 0
(1900 2175);
DISPLAY 0.489362 (1900 2175);
PAINT SKYBLUE (1900 2175);
FORCEPROP 1 LAST VOLTAGE 10V
J 0
(1900 2325);
DISPLAY 0.489362 (1900 2325);
PAINT SKYBLUE (1900 2325);
FORCEPROP 1 LAST PACK_TYPE C0402
J 0
(1900 2125);
DISPLAY 0.489362 (1900 2125);
PAINT SKYBLUE (1900 2125);
FORCEPROP 2 LAST CDS_LIB pure_quanta
J 0
(1850 2325);
DISPLAY INVISIBLE (1850 2325);
FORCEPROP 1 LAST PATH I115
J 0
(1900 2475);
DISPLAY 0.978723 (1900 2475);
PAINT WHITE (1900 2475);
DISPLAY INVISIBLE (1900 2475);
FORCEADD UNIVERSAL_GND..1
(1850 2125);
FORCEPROP 3 LASTPIN (1850 2175) SIG_NAME GND\g
J 0
(1860 2185);
DISPLAY 0.659574 (1860 2185);
PAINT MONO (1860 2185);
DISPLAY INVISIBLE (1860 2185);
FORCEPROP 2 LAST CDS_LIB pure_quanta_power
J 0
(1850 2125);
DISPLAY INVISIBLE (1850 2125);
FORCEPROP 1 LAST PATH I116
J 0
(1925 2125);
DISPLAY 0.872340 (1925 2125);
PAINT AQUA (1925 2125);
DISPLAY INVISIBLE (1925 2125);
FORCEPROP 1 LAST HDL_POWER GND
J 1
(1875 2050);
DISPLAY 0.872340 (1875 2050);
PAINT GREEN (1875 2050);
DISPLAY INVISIBLE (1875 2050);
FORCEADD OFFPAGE..5
(1875 1900);
FORCEPROP 2 LAST $XR0 176 
J 0
(1590 1900);
DISPLAY 0.638298 (1590 1900);
PAINT MONO (1590 1900);
FORCEPROP 2 LAST CDS_LIB standard
J 0
(1875 1900);
DISPLAY INVISIBLE (1875 1900);
FORCEPROP 1 LAST OFFPAGE TRUE
J 0
(2200 1775);
DISPLAY 0.872340 (2200 1775);
PAINT GREEN (2200 1775);
DISPLAY INVISIBLE (2200 1775);
FORCEPROP 1 LAST COMMENT_BODY TRUE
J 0
(1975 1825);
DISPLAY 0.872340 (1975 1825);
PAINT GREEN (1975 1825);
DISPLAY INVISIBLE (1975 1825);
FORCEPROP 2 LAST PATH I117
J 0
(1600 1950);
DISPLAY 1.021277 (1600 1950);
DISPLAY INVISIBLE (1600 1950);
FORCEADD OFFPAGE..1
(1875 1800);
FORCEPROP 2 LAST $XR5 182 
J 0
(1023 1800);
DISPLAY 0.638298 (1023 1800);
PAINT MONO (1023 1800);
FORCEPROP 2 LAST $XR4 181 
J 0
(1143 1800);
DISPLAY 0.638298 (1143 1800);
PAINT MONO (1143 1800);
FORCEPROP 2 LAST $XR3 179 
J 0
(1263 1800);
DISPLAY 0.638298 (1263 1800);
PAINT MONO (1263 1800);
FORCEPROP 2 LAST $XR2 178 
J 0
(1383 1800);
DISPLAY 0.638298 (1383 1800);
PAINT MONO (1383 1800);
FORCEPROP 2 LAST $XR1 177 
J 0
(1503 1800);
DISPLAY 0.638298 (1503 1800);
PAINT MONO (1503 1800);
FORCEPROP 2 LAST $XR0 176 
J 0
(1623 1800);
DISPLAY 0.638298 (1623 1800);
PAINT MONO (1623 1800);
FORCEPROP 2 LAST CDS_LIB standard
J 0
(1875 1800);
DISPLAY INVISIBLE (1875 1800);
FORCEPROP 1 LAST OFFPAGE TRUE
J 0
(2200 1675);
DISPLAY 0.872340 (2200 1675);
PAINT GREEN (2200 1675);
DISPLAY INVISIBLE (2200 1675);
FORCEPROP 1 LAST COMMENT_BODY TRUE
J 0
(2000 1700);
DISPLAY 0.872340 (2000 1700);
PAINT GREEN (2000 1700);
DISPLAY INVISIBLE (2000 1700);
FORCEPROP 2 LAST PATH I118
J 0
(1625 1850);
DISPLAY 1.021277 (1625 1850);
DISPLAY INVISIBLE (1625 1850);
FORCEADD UNIVERSAL_GND..1
(3975 1175);
FORCEPROP 3 LASTPIN (3975 1225) SIG_NAME GND\g
J 0
(3985 1235);
DISPLAY 0.659574 (3985 1235);
PAINT MONO (3985 1235);
DISPLAY INVISIBLE (3985 1235);
FORCEPROP 2 LAST CDS_LIB pure_quanta_power
J 0
(3975 1175);
PAINT MONO (3975 1175);
DISPLAY INVISIBLE (3975 1175);
FORCEPROP 1 LAST PATH I119
J 0
(4050 1175);
DISPLAY 0.872340 (4050 1175);
PAINT AQUA (4050 1175);
DISPLAY INVISIBLE (4050 1175);
FORCEPROP 1 LAST HDL_POWER GND
J 1
(4000 1100);
DISPLAY 0.872340 (4000 1100);
PAINT GREEN (4000 1100);
DISPLAY INVISIBLE (4000 1100);
FORCEADD ISL99390FRZTR5935..1
(3325 1900);
FORCEPROP 1 LAST LOCATION PU11
J 0
(3025 2775);
DISPLAY 0.489362 (3025 2775);
PAINT SKYBLUE (3025 2775);
FORCEPROP 0 LAST $SEC 1
J 0
(3025 2975);
DISPLAY 0.680851 (3025 2975);
PAINT MONO (3025 2975);
DISPLAY INVISIBLE (3025 2975);
FORCEPROP 2 LAST CDS_SEC 1
J 0
(3025 2950);
DISPLAY 1.021277 (3025 2950);
DISPLAY INVISIBLE (3025 2950);
FORCEPROP 0 LASTPIN (3725 1450) $PN 2
J 0
(3735 1460);
DISPLAY 0.489362 (3735 1460);
PAINT MONO (3735 1460);
FORCEPROP 0 LASTPIN (3725 2250) $PN 33
J 0
(3735 2260);
DISPLAY 0.489362 (3735 2260);
PAINT MONO (3735 2260);
FORCEPROP 0 LASTPIN (2875 1650) $PN 31
J 2
(2865 1660);
DISPLAY 0.489362 (2865 1660);
PAINT MONO (2865 1660);
FORCEPROP 0 LASTPIN (2875 2050) $PN 35
J 2
(2865 2060);
DISPLAY 0.489362 (2865 2060);
PAINT MONO (2865 2060);
FORCEPROP 0 LASTPIN (3725 1600) $PN 6
J 0
(3735 1610);
DISPLAY 0.489362 (3735 1610);
PAINT MONO (3735 1610);
FORCEPROP 0 LASTPIN (3725 1550) $PN 41
J 0
(3735 1560);
DISPLAY 0.489362 (3735 1560);
PAINT MONO (3735 1560);
FORCEPROP 0 LASTPIN (2875 1900) $PN 38
J 2
(2865 1910);
DISPLAY 0.489362 (2865 1910);
PAINT MONO (2865 1910);
FORCEPROP 0 LASTPIN (2875 1600) $PN 37
J 2
(2865 1610);
DISPLAY 0.489362 (2865 1610);
PAINT MONO (2865 1610);
FORCEPROP 0 LASTPIN (3725 1400) $PN 5
J 0
(3735 1410);
DISPLAY 0.489362 (3735 1410);
PAINT MONO (3735 1410);
FORCEPROP 0 LASTPIN (3725 1350) $PN 7_9-20_24
J 0
(3735 1360);
DISPLAY 0.489362 (3735 1360);
PAINT MONO (3735 1360);
FORCEPROP 0 LASTPIN (3725 1300) $PN 40
J 0
(3735 1310);
DISPLAY 0.489362 (3735 1310);
PAINT MONO (3735 1310);
FORCEPROP 0 LASTPIN (3725 2000) $PN 32
J 0
(3735 2010);
DISPLAY 0.489362 (3735 2010);
PAINT MONO (3735 2010);
FORCEPROP 0 LASTPIN (2875 2550) $PN 4
J 2
(2865 2560);
DISPLAY 0.489362 (2865 2560);
PAINT MONO (2865 2560);
FORCEPROP 0 LASTPIN (2875 1300) $PN 34
J 2
(2865 1310);
DISPLAY 0.489362 (2865 1310);
PAINT MONO (2865 1310);
FORCEPROP 0 LASTPIN (2875 1800) $PN 39
J 2
(2865 1810);
DISPLAY 0.489362 (2865 1810);
PAINT MONO (2865 1810);
FORCEPROP 0 LASTPIN (3725 1900) $PN 10_19
J 0
(3735 1910);
DISPLAY 0.489362 (3735 1910);
PAINT MONO (3735 1910);
FORCEPROP 0 LASTPIN (2875 1400) $PN 36
J 2
(2865 1410);
DISPLAY 0.489362 (2865 1410);
PAINT MONO (2865 1410);
FORCEPROP 0 LASTPIN (2875 2250) $PN 3
J 2
(2865 2260);
DISPLAY 0.489362 (2865 2260);
PAINT MONO (2865 2260);
FORCEPROP 0 LASTPIN (3725 2550) $PN 25_29
J 0
(3735 2560);
DISPLAY 0.489362 (3735 2560);
PAINT MONO (3735 2560);
FORCEPROP 0 LASTPIN (3725 2500) $PN 30
J 0
(3735 2510);
DISPLAY 0.489362 (3735 2510);
PAINT MONO (3735 2510);
FORCEPROP 0 LASTPIN (3725 1650) $PN 1
J 0
(3735 1660);
DISPLAY 0.489362 (3735 1660);
PAINT MONO (3735 1660);
FORCEPROP 2 LAST PART_TYPE SMLF
J 0
(3025 2925);
DISPLAY 0.638298 (3025 2925);
FORCEPROP 1 LAST MATERIAL IC
J 0
(3025 2625);
DISPLAY 0.489362 (3025 2625);
PAINT SKYBLUE (3025 2625);
FORCEPROP 2 LAST VALUE ISL99390FRZ-TR5935
J 0
(3025 2875);
DISPLAY 0.489362 (3025 2875);
PAINT SKYBLUE (3025 2875);
FORCEPROP 1 LAST PART_NUMBER AL099390004
J 0
(3025 2700);
DISPLAY 0.489362 (3025 2700);
PAINT SKYBLUE (3025 2700);
FORCEPROP 1 LAST NEEDS_NO_SIZE TRUE
J 0
(3325 1900);
DISPLAY 0.723404 (3325 1900);
PAINT GREEN (3325 1900);
DISPLAY INVISIBLE (3325 1900);
FORCEPROP 1 LAST CDS_LMAN_SYM_OUTLINE -300,700,250,-650
J 0
(3325 1900);
DISPLAY 0.468085 (3325 1900);
PAINT GREEN (3325 1900);
DISPLAY INVISIBLE (3325 1900);
FORCEPROP 2 LAST CDS_LIB pure_quanta
J 0
(3325 1900);
DISPLAY INVISIBLE (3325 1900);
FORCEPROP 1 LAST PATH I120
J 0
(3325 1900);
DISPLAY 0.723404 (3325 1900);
PAINT GREEN (3325 1900);
DISPLAY INVISIBLE (3325 1900);
FORCEADD OFFPAGE..1
(1875 1300);
FORCEPROP 2 LAST $XR0 176 
J 0
(1623 1300);
DISPLAY 0.638298 (1623 1300);
PAINT MONO (1623 1300);
FORCEPROP 2 LAST CDS_LIB standard
J 0
(1875 1300);
DISPLAY INVISIBLE (1875 1300);
FORCEPROP 1 LAST OFFPAGE TRUE
J 0
(2200 1175);
DISPLAY 0.872340 (2200 1175);
PAINT GREEN (2200 1175);
DISPLAY INVISIBLE (2200 1175);
FORCEPROP 1 LAST COMMENT_BODY TRUE
J 0
(2000 1200);
DISPLAY 0.872340 (2000 1200);
PAINT GREEN (2000 1200);
DISPLAY INVISIBLE (2000 1200);
FORCEPROP 2 LAST PATH I121
J 0
(1625 1350);
DISPLAY 1.021277 (1625 1350);
DISPLAY INVISIBLE (1625 1350);
FORCEADD OFFPAGE..5
(1875 1400);
FORCEPROP 2 LAST $XR3 176 
J 0
(1590 1472);
DISPLAY 0.638298 (1590 1472);
PAINT MONO (1590 1472);
FORCEPROP 2 LAST $XR2 179 
J 0
(1590 1436);
DISPLAY 0.638298 (1590 1436);
PAINT MONO (1590 1436);
FORCEPROP 2 LAST $XR1 178 
J 0
(1590 1364);
DISPLAY 0.638298 (1590 1364);
PAINT MONO (1590 1364);
FORCEPROP 2 LAST $XR0 177 
J 0
(1590 1400);
DISPLAY 0.638298 (1590 1400);
PAINT MONO (1590 1400);
FORCEPROP 2 LAST CDS_LIB standard
J 0
(1875 1400);
DISPLAY INVISIBLE (1875 1400);
FORCEPROP 1 LAST OFFPAGE TRUE
J 0
(2200 1275);
DISPLAY 0.872340 (2200 1275);
PAINT GREEN (2200 1275);
DISPLAY INVISIBLE (2200 1275);
FORCEPROP 1 LAST COMMENT_BODY TRUE
J 0
(1975 1325);
DISPLAY 0.872340 (1975 1325);
PAINT GREEN (1975 1325);
DISPLAY INVISIBLE (1975 1325);
FORCEPROP 2 LAST PATH I122
J 0
(1600 1475);
DISPLAY 1.021277 (1600 1475);
DISPLAY INVISIBLE (1600 1475);
FORCEADD Q_RES..2
R 2
(1400 1400);
FORCEPROP 1 LAST LOCATION PR7
J 2
(1355 1525);
DISPLAY 0.489362 (1355 1525);
PAINT SKYBLUE (1355 1525);
FORCEPROP 0 LAST $SEC 1
J 0
(1375 1575);
DISPLAY 0.680851 (1375 1575);
PAINT MONO (1375 1575);
DISPLAY INVISIBLE (1375 1575);
FORCEPROP 0 LAST CDS_SEC 1
J 0
(1375 1575);
DISPLAY 1.021277 (1375 1575);
DISPLAY INVISIBLE (1375 1575);
FORCEPROP 1 LASTPIN (1400 1500) $PN 1
J 2
(1395 1462);
DISPLAY 0.489362 (1395 1462);
PAINT MONO (1395 1462);
FORCEPROP 1 LASTPIN (1400 1300) $PN 2
J 2
(1395 1310);
DISPLAY 0.489362 (1395 1310);
PAINT MONO (1395 1310);
FORCEPROP 1 LAST WATTAGE 1/16W
J 2
(1360 1375);
DISPLAY 0.489362 (1360 1375);
PAINT SKYBLUE (1360 1375);
FORCEPROP 1 LAST MATERIAL EMPTY
J 2
(1360 1325);
DISPLAY 0.489362 (1360 1325);
PAINT RED (1360 1325);
FORCEPROP 1 LAST TOLERANCE 1%
J 2
(1355 1425);
DISPLAY 0.489362 (1355 1425);
PAINT SKYBLUE (1355 1425);
FORCEPROP 1 LAST VALUE 8.87K
J 2
(1355 1475);
DISPLAY 0.489362 (1355 1475);
PAINT SKYBLUE (1355 1475);
FORCEPROP 1 LAST PART_NUMBER CS28872FB01
J 2
(1360 1275);
DISPLAY 0.489362 (1360 1275);
PAINT SKYBLUE (1360 1275);
FORCEPROP 1 LAST PACK_TYPE 0402LF
J 2
(1360 1225);
DISPLAY 0.489362 (1360 1225);
PAINT SKYBLUE (1360 1225);
FORCEPROP 2 LAST CDS_LIB pure_quanta
J 2
(1400 1400);
DISPLAY INVISIBLE (1400 1400);
FORCEPROP 1 LAST PATH I123
J 2
(1350 1575);
DISPLAY 0.978723 (1350 1575);
PAINT WHITE (1350 1575);
DISPLAY INVISIBLE (1350 1575);
FORCEADD UNIVERSAL_GND..1
(1400 1175);
FORCEPROP 3 LASTPIN (1400 1225) SIG_NAME GND\g
J 0
(1410 1235);
DISPLAY 0.659574 (1410 1235);
PAINT MONO (1410 1235);
DISPLAY INVISIBLE (1410 1235);
FORCEPROP 2 LAST CDS_LIB pure_quanta_power
J 0
(1400 1175);
PAINT MONO (1400 1175);
DISPLAY INVISIBLE (1400 1175);
FORCEPROP 1 LAST PATH I124
J 0
(1475 1175);
DISPLAY 0.872340 (1475 1175);
PAINT AQUA (1475 1175);
DISPLAY INVISIBLE (1475 1175);
FORCEPROP 1 LAST HDL_POWER GND
J 1
(1425 1100);
DISPLAY 0.872340 (1425 1100);
PAINT GREEN (1425 1100);
DISPLAY INVISIBLE (1425 1100);
FORCEADD Q_CAP..1
(900 1525);
FORCEPROP 1 LAST LOCATION PC111_6
J 0
(950 1625);
DISPLAY 0.489362 (950 1625);
PAINT SKYBLUE (950 1625);
FORCEPROP 0 LAST $SEC 1
J 0
(950 1650);
DISPLAY 0.680851 (950 1650);
PAINT MONO (950 1650);
DISPLAY INVISIBLE (950 1650);
FORCEPROP 0 LAST CDS_SEC 1
J 0
(1150 1575);
DISPLAY 1.021277 (1150 1575);
DISPLAY INVISIBLE (1150 1575);
FORCEPROP 1 LASTPIN (900 1625) $PN 1
J 0
(910 1605);
DISPLAY 0.489362 (910 1605);
PAINT MONO (910 1605);
FORCEPROP 1 LASTPIN (900 1425) $PN 2
J 0
(910 1405);
DISPLAY 0.489362 (910 1405);
PAINT MONO (910 1405);
FORCEPROP 1 LAST MATERIAL X7R
J 0
(950 1425);
DISPLAY 0.489362 (950 1425);
PAINT SKYBLUE (950 1425);
FORCEPROP 1 LAST TOLERANCE 10%
J 0
(950 1475);
DISPLAY 0.489362 (950 1475);
PAINT SKYBLUE (950 1475);
FORCEPROP 1 LAST VALUE 0.1UF
J 0
(950 1575);
DISPLAY 0.489362 (950 1575);
PAINT SKYBLUE (950 1575);
FORCEPROP 1 LAST PART_NUMBER CH4104K1B00
J 0
(950 1375);
DISPLAY 0.489362 (950 1375);
PAINT SKYBLUE (950 1375);
FORCEPROP 1 LAST VOLTAGE 25V
J 0
(950 1525);
DISPLAY 0.489362 (950 1525);
PAINT SKYBLUE (950 1525);
FORCEPROP 1 LAST PACK_TYPE 0402
J 0
(950 1325);
DISPLAY 0.489362 (950 1325);
PAINT SKYBLUE (950 1325);
FORCEPROP 2 LAST CDS_LIB pure_quanta
J 0
(900 1525);
DISPLAY INVISIBLE (900 1525);
FORCEPROP 1 LAST PATH I125
J 0
(950 1675);
DISPLAY 0.978723 (950 1675);
PAINT WHITE (950 1675);
DISPLAY INVISIBLE (950 1675);
FORCEADD UNIVERSAL_GND..1
(900 1325);
FORCEPROP 3 LASTPIN (900 1375) SIG_NAME GND\g
J 0
(910 1385);
DISPLAY 0.659574 (910 1385);
PAINT MONO (910 1385);
DISPLAY INVISIBLE (910 1385);
FORCEPROP 2 LAST CDS_LIB pure_quanta_power
J 0
(900 1325);
DISPLAY INVISIBLE (900 1325);
FORCEPROP 1 LAST PATH I126
J 0
(975 1325);
DISPLAY 0.872340 (975 1325);
PAINT AQUA (975 1325);
DISPLAY INVISIBLE (975 1325);
FORCEPROP 1 LAST HDL_POWER GND
J 1
(925 1250);
DISPLAY 0.872340 (925 1250);
PAINT GREEN (925 1250);
DISPLAY INVISIBLE (925 1250);
FORCEADD UNIVERSAL_GND..1
(4850 3600);
FORCEPROP 3 LASTPIN (4850 3650) SIG_NAME GND\g
J 0
(4860 3660);
DISPLAY 0.659574 (4860 3660);
PAINT MONO (4860 3660);
DISPLAY INVISIBLE (4860 3660);
FORCEPROP 2 LAST CDS_LIB pure_quanta_power
J 0
(4850 3600);
DISPLAY INVISIBLE (4850 3600);
FORCEPROP 1 LAST PATH I127
J 0
(4925 3600);
DISPLAY 0.872340 (4925 3600);
PAINT AQUA (4925 3600);
DISPLAY INVISIBLE (4925 3600);
FORCEPROP 1 LAST HDL_POWER GND
J 1
(4875 3525);
DISPLAY 0.872340 (4875 3525);
PAINT GREEN (4875 3525);
DISPLAY INVISIBLE (4875 3525);
FORCEADD Q_RES..2
(4850 3825);
FORCEPROP 1 LAST LOCATION PR158
J 0
(4895 3950);
DISPLAY 0.489362 (4895 3950);
PAINT SKYBLUE (4895 3950);
FORCEPROP 0 LAST $SEC 1
J 0
(4900 4000);
DISPLAY 0.680851 (4900 4000);
PAINT MONO (4900 4000);
DISPLAY INVISIBLE (4900 4000);
FORCEPROP 0 LAST CDS_SEC 1
J 0
(4900 4000);
DISPLAY 1.021277 (4900 4000);
DISPLAY INVISIBLE (4900 4000);
FORCEPROP 1 LASTPIN (4850 3925) $PN 1
J 0
(4855 3887);
DISPLAY 0.489362 (4855 3887);
PAINT MONO (4855 3887);
FORCEPROP 1 LASTPIN (4850 3725) $PN 2
J 0
(4855 3735);
DISPLAY 0.489362 (4855 3735);
PAINT MONO (4855 3735);
FORCEPROP 1 LAST WATTAGE 1/8W
J 0
(4890 3800);
DISPLAY 0.489362 (4890 3800);
PAINT SKYBLUE (4890 3800);
FORCEPROP 1 LAST MATERIAL EMPTY
J 0
(4890 3750);
DISPLAY 0.489362 (4890 3750);
PAINT RED (4890 3750);
FORCEPROP 1 LAST TOLERANCE 1%
J 0
(4895 3850);
DISPLAY 0.489362 (4895 3850);
PAINT SKYBLUE (4895 3850);
FORCEPROP 1 LAST VALUE 1.5
J 0
(4895 3900);
DISPLAY 0.489362 (4895 3900);
PAINT SKYBLUE (4895 3900);
FORCEPROP 1 LAST PART_NUMBER CS-1504FB00
J 0
(4890 3700);
DISPLAY 0.489362 (4890 3700);
PAINT SKYBLUE (4890 3700);
FORCEPROP 1 LAST PACK_TYPE 0402LF
J 0
(4890 3650);
DISPLAY 0.489362 (4890 3650);
PAINT SKYBLUE (4890 3650);
FORCEPROP 2 LAST CDS_LIB pure_quanta
J 0
(4850 3825);
DISPLAY INVISIBLE (4850 3825);
FORCEPROP 1 LAST PATH I128
J 0
(4900 4000);
DISPLAY 0.978723 (4900 4000);
PAINT WHITE (4900 4000);
DISPLAY INVISIBLE (4900 4000);
FORCEADD Q_CAP..1
(4850 4350);
FORCEPROP 1 LAST LOCATION PC157
J 0
(4900 4450);
DISPLAY 0.489362 (4900 4450);
PAINT SKYBLUE (4900 4450);
FORCEPROP 0 LAST $SEC 1
J 0
(4900 4500);
DISPLAY 0.680851 (4900 4500);
PAINT MONO (4900 4500);
DISPLAY INVISIBLE (4900 4500);
FORCEPROP 0 LAST CDS_SEC 1
J 0
(4900 4500);
DISPLAY 1.021277 (4900 4500);
DISPLAY INVISIBLE (4900 4500);
FORCEPROP 1 LASTPIN (4850 4450) $PN 1
J 0
(4860 4430);
DISPLAY 0.489362 (4860 4430);
PAINT MONO (4860 4430);
FORCEPROP 1 LASTPIN (4850 4250) $PN 2
J 0
(4860 4230);
DISPLAY 0.489362 (4860 4230);
PAINT MONO (4860 4230);
FORCEPROP 1 LAST MATERIAL EMPTY
J 0
(4900 4250);
DISPLAY 0.489362 (4900 4250);
PAINT RED (4900 4250);
FORCEPROP 1 LAST TOLERANCE 10%
J 0
(4900 4300);
DISPLAY 0.489362 (4900 4300);
PAINT SKYBLUE (4900 4300);
FORCEPROP 1 LAST VALUE 560PF
J 0
(4900 4400);
DISPLAY 0.489362 (4900 4400);
PAINT SKYBLUE (4900 4400);
FORCEPROP 1 LAST PART_NUMBER CH1566K1B09
J 0
(4900 4200);
DISPLAY 0.489362 (4900 4200);
PAINT SKYBLUE (4900 4200);
FORCEPROP 1 LAST VOLTAGE 50V
J 0
(4900 4350);
DISPLAY 0.489362 (4900 4350);
PAINT SKYBLUE (4900 4350);
FORCEPROP 1 LAST PACK_TYPE C0402
J 0
(4900 4150);
DISPLAY 0.489362 (4900 4150);
PAINT SKYBLUE (4900 4150);
FORCEPROP 2 LAST CDS_LIB pure_quanta
J 0
(4850 4350);
DISPLAY INVISIBLE (4850 4350);
FORCEPROP 1 LAST PATH I129
J 0
(4900 4500);
DISPLAY 0.978723 (4900 4500);
PAINT WHITE (4900 4500);
DISPLAY INVISIBLE (4900 4500);
FORCEADD UNIVERSAL_GND..1
(4750 925);
FORCEPROP 3 LASTPIN (4750 975) SIG_NAME GND\g
J 0
(4760 985);
DISPLAY 0.659574 (4760 985);
PAINT MONO (4760 985);
DISPLAY INVISIBLE (4760 985);
FORCEPROP 2 LAST CDS_LIB pure_quanta_power
J 0
(4750 925);
DISPLAY INVISIBLE (4750 925);
FORCEPROP 1 LAST PATH I130
J 0
(4825 925);
DISPLAY 0.872340 (4825 925);
PAINT AQUA (4825 925);
DISPLAY INVISIBLE (4825 925);
FORCEPROP 1 LAST HDL_POWER GND
J 1
(4775 850);
DISPLAY 0.872340 (4775 850);
PAINT GREEN (4775 850);
DISPLAY INVISIBLE (4775 850);
FORCEADD Q_RES..2
(4750 1150);
FORCEPROP 1 LAST LOCATION PR155
J 0
(4795 1275);
DISPLAY 0.489362 (4795 1275);
PAINT SKYBLUE (4795 1275);
FORCEPROP 0 LAST $SEC 1
J 0
(4800 1325);
DISPLAY 0.680851 (4800 1325);
PAINT MONO (4800 1325);
DISPLAY INVISIBLE (4800 1325);
FORCEPROP 0 LAST CDS_SEC 1
J 0
(4800 1325);
DISPLAY 1.021277 (4800 1325);
DISPLAY INVISIBLE (4800 1325);
FORCEPROP 1 LASTPIN (4750 1250) $PN 1
J 0
(4755 1212);
DISPLAY 0.489362 (4755 1212);
PAINT MONO (4755 1212);
FORCEPROP 1 LASTPIN (4750 1050) $PN 2
J 0
(4755 1060);
DISPLAY 0.489362 (4755 1060);
PAINT MONO (4755 1060);
FORCEPROP 1 LAST TOLERANCE 1%
J 0
(4795 1175);
DISPLAY 0.489362 (4795 1175);
PAINT SKYBLUE (4795 1175);
FORCEPROP 1 LAST WATTAGE 1/8W
J 0
(4790 1125);
DISPLAY 0.489362 (4790 1125);
PAINT SKYBLUE (4790 1125);
FORCEPROP 1 LAST VALUE 1.5
J 0
(4795 1225);
DISPLAY 0.489362 (4795 1225);
PAINT SKYBLUE (4795 1225);
FORCEPROP 1 LAST PART_NUMBER CS-1504FB00
J 0
(4790 1025);
DISPLAY 0.489362 (4790 1025);
PAINT SKYBLUE (4790 1025);
FORCEPROP 1 LAST PACK_TYPE 0402LF
J 0
(4790 975);
DISPLAY 0.489362 (4790 975);
PAINT SKYBLUE (4790 975);
FORCEPROP 1 LAST MATERIAL EMPTY
J 0
(4790 1075);
DISPLAY 0.489362 (4790 1075);
PAINT RED (4790 1075);
FORCEPROP 2 LAST CDS_LIB pure_quanta
J 0
(4750 1150);
DISPLAY INVISIBLE (4750 1150);
FORCEPROP 1 LAST PATH I131
J 0
(4800 1325);
DISPLAY 0.978723 (4800 1325);
PAINT WHITE (4800 1325);
DISPLAY INVISIBLE (4800 1325);
FORCEADD Q_CAP..1
(4750 1700);
FORCEPROP 1 LAST LOCATION PC154
J 0
(4800 1800);
DISPLAY 0.489362 (4800 1800);
PAINT SKYBLUE (4800 1800);
FORCEPROP 0 LAST $SEC 1
J 0
(4800 1850);
DISPLAY 0.680851 (4800 1850);
PAINT MONO (4800 1850);
DISPLAY INVISIBLE (4800 1850);
FORCEPROP 0 LAST CDS_SEC 1
J 0
(4800 1850);
DISPLAY 1.021277 (4800 1850);
DISPLAY INVISIBLE (4800 1850);
FORCEPROP 1 LASTPIN (4750 1800) $PN 1
J 0
(4760 1780);
DISPLAY 0.489362 (4760 1780);
PAINT MONO (4760 1780);
FORCEPROP 1 LASTPIN (4750 1600) $PN 2
J 0
(4760 1580);
DISPLAY 0.489362 (4760 1580);
PAINT MONO (4760 1580);
FORCEPROP 1 LAST PART_NUMBER CH1566K1B09
J 0
(4800 1550);
DISPLAY 0.489362 (4800 1550);
PAINT SKYBLUE (4800 1550);
FORCEPROP 1 LAST VALUE 560PF
J 0
(4800 1750);
DISPLAY 0.489362 (4800 1750);
PAINT SKYBLUE (4800 1750);
FORCEPROP 1 LAST PACK_TYPE C0402
J 0
(4800 1500);
DISPLAY 0.489362 (4800 1500);
PAINT SKYBLUE (4800 1500);
FORCEPROP 1 LAST MATERIAL EMPTY
J 0
(4800 1600);
DISPLAY 0.489362 (4800 1600);
PAINT RED (4800 1600);
FORCEPROP 1 LAST TOLERANCE 10%
J 0
(4800 1650);
DISPLAY 0.489362 (4800 1650);
PAINT SKYBLUE (4800 1650);
FORCEPROP 1 LAST VOLTAGE 50V
J 0
(4800 1700);
DISPLAY 0.489362 (4800 1700);
PAINT SKYBLUE (4800 1700);
FORCEPROP 2 LAST CDS_LIB pure_quanta
J 0
(4750 1700);
DISPLAY INVISIBLE (4750 1700);
FORCEPROP 1 LAST PATH I132
J 0
(4800 1850);
DISPLAY 0.978723 (4800 1850);
PAINT WHITE (4800 1850);
DISPLAY INVISIBLE (4800 1850);
FORCEADD VCC_CORE..1
(1875 5950);
FORCEPROP 3 LASTPIN (1875 5900) SIG_NAME PVDDCR_CPU1_P0_PVCC\g
J 0
(1885 5910);
DISPLAY 0.659574 (1885 5910);
PAINT MONO (1885 5910);
DISPLAY INVISIBLE (1885 5910);
FORCEPROP 1 LAST HDL_POWER PVDDCR_CPU1_P0_PVCC
J 1
(1875 6000);
DISPLAY 0.489362 (1875 6000);
PAINT GREEN (1875 6000);
FORCEPROP 2 LAST CDS_LIB pure_quanta_power
J 0
(1875 5950);
DISPLAY INVISIBLE (1875 5950);
FORCEPROP 1 LAST PATH I133
J 0
(1925 5975);
DISPLAY 0.872340 (1925 5975);
PAINT AQUA (1925 5975);
DISPLAY INVISIBLE (1925 5975);
FORCEADD VCC_CORE..1
(1850 3300);
FORCEPROP 3 LASTPIN (1850 3250) SIG_NAME PVDDCR_CPU1_P0_PVCC\g
J 0
(1860 3260);
DISPLAY 0.659574 (1860 3260);
PAINT MONO (1860 3260);
DISPLAY INVISIBLE (1860 3260);
FORCEPROP 1 LAST HDL_POWER PVDDCR_CPU1_P0_PVCC
J 1
(1850 3350);
DISPLAY 0.489362 (1850 3350);
PAINT GREEN (1850 3350);
FORCEPROP 2 LAST CDS_LIB pure_quanta_power
J 0
(1850 3300);
DISPLAY INVISIBLE (1850 3300);
FORCEPROP 1 LAST PATH I134
J 0
(1900 3325);
DISPLAY 0.872340 (1900 3325);
PAINT AQUA (1900 3325);
DISPLAY INVISIBLE (1900 3325);
FORCEADD UNIVERSAL_GND..1
(5100 1550);
FORCEPROP 3 LASTPIN (5100 1600) SIG_NAME GND\g
J 0
(5110 1610);
DISPLAY 0.659574 (5110 1610);
PAINT MONO (5110 1610);
DISPLAY INVISIBLE (5110 1610);
FORCEPROP 2 LAST CDS_LIB pure_quanta_power
J 0
(5100 1550);
DISPLAY INVISIBLE (5100 1550);
FORCEPROP 1 LAST PATH I135
J 0
(5175 1550);
DISPLAY 0.872340 (5175 1550);
PAINT AQUA (5175 1550);
DISPLAY INVISIBLE (5175 1550);
FORCEPROP 1 LAST HDL_POWER GND
J 1
(5125 1475);
DISPLAY 0.872340 (5125 1475);
PAINT GREEN (5125 1475);
DISPLAY INVISIBLE (5125 1475);
FORCEADD Q_INDUCTOR..1
R 2
(5275 1675);
FORCEPROP 1 LAST LOCATION PL9
J 0
(5125 1825);
DISPLAY 0.489362 (5125 1825);
PAINT SKYBLUE (5125 1825);
FORCEPROP 0 LAST $SEC 1
J 0
(5125 1850);
DISPLAY 0.680851 (5125 1850);
PAINT MONO (5125 1850);
DISPLAY INVISIBLE (5125 1850);
FORCEPROP 0 LAST CDS_SEC 1
J 0
(5125 1850);
DISPLAY 0.680851 (5125 1850);
DISPLAY INVISIBLE (5125 1850);
FORCEPROP 0 LASTPIN (5375 1650) $PN 1
J 0
(5385 1660);
DISPLAY 0.489362 (5385 1660);
PAINT MONO (5385 1660);
FORCEPROP 0 LASTPIN (5175 1650) $PN 2
J 2
(5165 1660);
DISPLAY 0.489362 (5165 1660);
PAINT MONO (5165 1660);
FORCEPROP 2 LASTPIN (5375 1650) SIG_NAME IND_CPU1_P0_CPL0
J 0
(5390 1660);
DISPLAY 0.489362 (5390 1660);
FORCEPROP 2 LASTPROP $XRERR UNIQUE?
J 0
(5150 1660);
DISPLAY 0.638298 (5150 1660);
PAINT MONO (5150 1660);
DISPLAY INVISIBLE (5150 1660);
FORCEPROP 2 LAST PACK_TYPE SMLF
J 0
(5125 1775);
DISPLAY 0.489362 (5125 1775);
PAINT SKYBLUE (5125 1775);
FORCEPROP 1 LAST MATERIAL IND
J 0
(5125 1725);
DISPLAY 0.489362 (5125 1725);
PAINT SKYBLUE (5125 1725);
FORCEPROP 2 LAST VALUE 0.22UH/33A
J 0
(5125 1800);
DISPLAY 0.489362 (5125 1800);
PAINT SKYBLUE (5125 1800);
FORCEPROP 1 LAST PART_NUMBER CV+22Y0EZ00
J 0
(5125 1750);
DISPLAY 0.489362 (5125 1750);
PAINT SKYBLUE (5125 1750);
FORCEPROP 1 LAST PATH I136
J 2
(5200 1730);
DISPLAY 0.723404 (5200 1730);
PAINT GREEN (5200 1730);
DISPLAY INVISIBLE (5200 1730);
FORCEPROP 1 LAST NEEDS_NO_SIZE TRUE
J 2
(5275 1675);
DISPLAY 0.468085 (5275 1675);
PAINT GREEN (5275 1675);
DISPLAY INVISIBLE (5275 1675);
FORCEPROP 2 LAST CDS_LIB pure_quanta
J 0
(5275 1675);
DISPLAY INVISIBLE (5275 1675);
FORCEADD UNIVERSAL_GND..1
(1425 3825);
FORCEPROP 3 LASTPIN (1425 3875) SIG_NAME GND\g
J 0
(1435 3885);
DISPLAY 0.659574 (1435 3885);
PAINT MONO (1435 3885);
DISPLAY INVISIBLE (1435 3885);
FORCEPROP 2 LAST CDS_LIB pure_quanta_power
J 0
(1425 3825);
PAINT MONO (1425 3825);
DISPLAY INVISIBLE (1425 3825);
FORCEPROP 1 LAST PATH I20
J 0
(1500 3825);
DISPLAY 0.872340 (1500 3825);
PAINT AQUA (1500 3825);
DISPLAY INVISIBLE (1500 3825);
FORCEPROP 1 LAST HDL_POWER GND
J 1
(1450 3750);
DISPLAY 0.872340 (1450 3750);
PAINT GREEN (1450 3750);
DISPLAY INVISIBLE (1450 3750);
FORCEADD Q_RES..2
R 2
(1425 4050);
FORCEPROP 1 LAST LOCATION PR93
J 2
(1380 4175);
DISPLAY 0.489362 (1380 4175);
PAINT SKYBLUE (1380 4175);
FORCEPROP 0 LAST $SEC 1
J 0
(1400 4225);
DISPLAY 0.680851 (1400 4225);
PAINT MONO (1400 4225);
DISPLAY INVISIBLE (1400 4225);
FORCEPROP 0 LAST CDS_SEC 1
J 0
(1400 4225);
DISPLAY 1.021277 (1400 4225);
DISPLAY INVISIBLE (1400 4225);
FORCEPROP 1 LASTPIN (1425 4150) $PN 1
J 2
(1420 4112);
DISPLAY 0.489362 (1420 4112);
PAINT MONO (1420 4112);
FORCEPROP 1 LASTPIN (1425 3950) $PN 2
J 2
(1420 3960);
DISPLAY 0.489362 (1420 3960);
PAINT MONO (1420 3960);
FORCEPROP 1 LAST PART_NUMBER CS28872FB01
J 2
(1385 3925);
DISPLAY 0.489362 (1385 3925);
PAINT SKYBLUE (1385 3925);
FORCEPROP 1 LAST WATTAGE 1/16W
J 2
(1385 4025);
DISPLAY 0.489362 (1385 4025);
PAINT SKYBLUE (1385 4025);
FORCEPROP 1 LAST MATERIAL EMPTY
J 2
(1385 3975);
DISPLAY 0.489362 (1385 3975);
PAINT RED (1385 3975);
FORCEPROP 1 LAST TOLERANCE 1%
J 2
(1380 4075);
DISPLAY 0.489362 (1380 4075);
PAINT SKYBLUE (1380 4075);
FORCEPROP 1 LAST VALUE 8.87K
J 2
(1380 4125);
DISPLAY 0.489362 (1380 4125);
PAINT SKYBLUE (1380 4125);
FORCEPROP 1 LAST PACK_TYPE 0402LF
J 2
(1385 3875);
DISPLAY 0.489362 (1385 3875);
PAINT SKYBLUE (1385 3875);
FORCEPROP 2 LAST CDS_LIB pure_quanta
J 2
(1425 4050);
DISPLAY INVISIBLE (1425 4050);
FORCEPROP 1 LAST PATH I21
J 2
(1375 4225);
DISPLAY 0.978723 (1375 4225);
PAINT WHITE (1375 4225);
DISPLAY INVISIBLE (1375 4225);
FORCEADD OFFPAGE..1
(1900 3950);
FORCEPROP 2 LAST $XR0 176 
J 0
(1648 3950);
DISPLAY 0.638298 (1648 3950);
PAINT MONO (1648 3950);
FORCEPROP 2 LAST CDS_LIB standard
J 0
(1900 3950);
DISPLAY INVISIBLE (1900 3950);
FORCEPROP 1 LAST OFFPAGE TRUE
J 0
(2225 3825);
DISPLAY 0.872340 (2225 3825);
PAINT GREEN (2225 3825);
DISPLAY INVISIBLE (2225 3825);
FORCEPROP 1 LAST COMMENT_BODY TRUE
J 0
(2025 3850);
DISPLAY 0.872340 (2025 3850);
PAINT GREEN (2025 3850);
DISPLAY INVISIBLE (2025 3850);
FORCEPROP 2 LAST PATH I23
J 0
(1475 4000);
DISPLAY 1.021277 (1475 4000);
DISPLAY INVISIBLE (1475 4000);
FORCEADD OFFPAGE..5
(1900 4050);
FORCEPROP 2 LAST $XR3 176 
J 0
(1615 4122);
DISPLAY 0.638298 (1615 4122);
PAINT MONO (1615 4122);
FORCEPROP 2 LAST $XR2 179 
J 0
(1615 4086);
DISPLAY 0.638298 (1615 4086);
PAINT MONO (1615 4086);
FORCEPROP 2 LAST $XR1 178 
J 0
(1615 4014);
DISPLAY 0.638298 (1615 4014);
PAINT MONO (1615 4014);
FORCEPROP 2 LAST $XR0 177 
J 0
(1615 4050);
DISPLAY 0.638298 (1615 4050);
PAINT MONO (1615 4050);
FORCEPROP 2 LAST CDS_LIB standard
J 0
(1900 4050);
DISPLAY INVISIBLE (1900 4050);
FORCEPROP 1 LAST OFFPAGE TRUE
J 0
(2225 3925);
DISPLAY 0.872340 (2225 3925);
PAINT GREEN (2225 3925);
DISPLAY INVISIBLE (2225 3925);
FORCEPROP 1 LAST COMMENT_BODY TRUE
J 0
(2000 3975);
DISPLAY 0.872340 (2000 3975);
PAINT GREEN (2000 3975);
DISPLAY INVISIBLE (2000 3975);
FORCEPROP 2 LAST PATH I25
J 0
(1625 4200);
DISPLAY 1.021277 (1625 4200);
DISPLAY INVISIBLE (1625 4200);
FORCEADD OFFPAGE..1
(1900 4450);
FORCEPROP 2 LAST $XR5 182 
J 0
(1048 4450);
DISPLAY 0.638298 (1048 4450);
PAINT MONO (1048 4450);
FORCEPROP 2 LAST $XR4 181 
J 0
(1168 4450);
DISPLAY 0.638298 (1168 4450);
PAINT MONO (1168 4450);
FORCEPROP 2 LAST $XR3 179 
J 0
(1288 4450);
DISPLAY 0.638298 (1288 4450);
PAINT MONO (1288 4450);
FORCEPROP 2 LAST $XR2 178 
J 0
(1408 4450);
DISPLAY 0.638298 (1408 4450);
PAINT MONO (1408 4450);
FORCEPROP 2 LAST $XR1 177 
J 0
(1528 4450);
DISPLAY 0.638298 (1528 4450);
PAINT MONO (1528 4450);
FORCEPROP 2 LAST $XR0 176 
J 0
(1648 4450);
DISPLAY 0.638298 (1648 4450);
PAINT MONO (1648 4450);
FORCEPROP 2 LAST CDS_LIB standard
J 0
(1900 4450);
DISPLAY INVISIBLE (1900 4450);
FORCEPROP 1 LAST OFFPAGE TRUE
J 0
(2225 4325);
DISPLAY 0.872340 (2225 4325);
PAINT GREEN (2225 4325);
DISPLAY INVISIBLE (2225 4325);
FORCEPROP 1 LAST COMMENT_BODY TRUE
J 0
(2025 4350);
DISPLAY 0.872340 (2025 4350);
PAINT GREEN (2025 4350);
DISPLAY INVISIBLE (2025 4350);
FORCEPROP 2 LAST PATH I26
J 0
(1650 4500);
DISPLAY 1.021277 (1650 4500);
DISPLAY INVISIBLE (1650 4500);
FORCEADD OFFPAGE..5
(1900 4550);
FORCEPROP 2 LAST $XR0 176 
J 0
(1615 4550);
DISPLAY 0.638298 (1615 4550);
PAINT MONO (1615 4550);
FORCEPROP 2 LAST CDS_LIB standard
J 0
(1900 4550);
DISPLAY INVISIBLE (1900 4550);
FORCEPROP 1 LAST OFFPAGE TRUE
J 0
(2225 4425);
DISPLAY 0.872340 (2225 4425);
PAINT GREEN (2225 4425);
DISPLAY INVISIBLE (2225 4425);
FORCEPROP 1 LAST COMMENT_BODY TRUE
J 0
(2000 4475);
DISPLAY 0.872340 (2000 4475);
PAINT GREEN (2000 4475);
DISPLAY INVISIBLE (2000 4475);
FORCEPROP 2 LAST PATH I28
J 0
(1625 4600);
DISPLAY 1.021277 (1625 4600);
DISPLAY INVISIBLE (1625 4600);
FORCEADD ISL99390FRZTR5935..1
(3350 4550);
FORCEPROP 1 LAST LOCATION PU16
J 0
(3050 5425);
DISPLAY 0.489362 (3050 5425);
PAINT SKYBLUE (3050 5425);
FORCEPROP 0 LAST $SEC 1
J 0
(3050 5625);
DISPLAY 0.680851 (3050 5625);
PAINT MONO (3050 5625);
DISPLAY INVISIBLE (3050 5625);
FORCEPROP 2 LAST CDS_SEC 1
J 0
(3050 5600);
DISPLAY 1.021277 (3050 5600);
DISPLAY INVISIBLE (3050 5600);
FORCEPROP 0 LASTPIN (3750 4100) $PN 2
J 0
(3760 4110);
DISPLAY 0.489362 (3760 4110);
PAINT MONO (3760 4110);
FORCEPROP 0 LASTPIN (3750 4900) $PN 33
J 0
(3760 4910);
DISPLAY 0.489362 (3760 4910);
PAINT MONO (3760 4910);
FORCEPROP 0 LASTPIN (2900 4300) $PN 31
J 2
(2890 4310);
DISPLAY 0.489362 (2890 4310);
PAINT MONO (2890 4310);
FORCEPROP 0 LASTPIN (2900 4700) $PN 35
J 2
(2890 4710);
DISPLAY 0.489362 (2890 4710);
PAINT MONO (2890 4710);
FORCEPROP 0 LASTPIN (3750 4250) $PN 6
J 0
(3760 4260);
DISPLAY 0.489362 (3760 4260);
PAINT MONO (3760 4260);
FORCEPROP 0 LASTPIN (3750 4200) $PN 41
J 0
(3760 4210);
DISPLAY 0.489362 (3760 4210);
PAINT MONO (3760 4210);
FORCEPROP 0 LASTPIN (2900 4550) $PN 38
J 2
(2890 4560);
DISPLAY 0.489362 (2890 4560);
PAINT MONO (2890 4560);
FORCEPROP 0 LASTPIN (2900 4250) $PN 37
J 2
(2890 4260);
DISPLAY 0.489362 (2890 4260);
PAINT MONO (2890 4260);
FORCEPROP 0 LASTPIN (3750 4050) $PN 5
J 0
(3760 4060);
DISPLAY 0.489362 (3760 4060);
PAINT MONO (3760 4060);
FORCEPROP 0 LASTPIN (3750 4000) $PN 7_9-20_24
J 0
(3760 4010);
DISPLAY 0.489362 (3760 4010);
PAINT MONO (3760 4010);
FORCEPROP 0 LASTPIN (3750 3950) $PN 40
J 0
(3760 3960);
DISPLAY 0.489362 (3760 3960);
PAINT MONO (3760 3960);
FORCEPROP 0 LASTPIN (3750 4650) $PN 32
J 0
(3760 4660);
DISPLAY 0.489362 (3760 4660);
PAINT MONO (3760 4660);
FORCEPROP 0 LASTPIN (2900 5200) $PN 4
J 2
(2890 5210);
DISPLAY 0.489362 (2890 5210);
PAINT MONO (2890 5210);
FORCEPROP 0 LASTPIN (2900 3950) $PN 34
J 2
(2890 3960);
DISPLAY 0.489362 (2890 3960);
PAINT MONO (2890 3960);
FORCEPROP 0 LASTPIN (2900 4450) $PN 39
J 2
(2890 4460);
DISPLAY 0.489362 (2890 4460);
PAINT MONO (2890 4460);
FORCEPROP 0 LASTPIN (3750 4550) $PN 10_19
J 0
(3760 4560);
DISPLAY 0.489362 (3760 4560);
PAINT MONO (3760 4560);
FORCEPROP 0 LASTPIN (2900 4050) $PN 36
J 2
(2890 4060);
DISPLAY 0.489362 (2890 4060);
PAINT MONO (2890 4060);
FORCEPROP 0 LASTPIN (2900 4900) $PN 3
J 2
(2890 4910);
DISPLAY 0.489362 (2890 4910);
PAINT MONO (2890 4910);
FORCEPROP 0 LASTPIN (3750 5200) $PN 25_29
J 0
(3760 5210);
DISPLAY 0.489362 (3760 5210);
PAINT MONO (3760 5210);
FORCEPROP 0 LASTPIN (3750 5150) $PN 30
J 0
(3760 5160);
DISPLAY 0.489362 (3760 5160);
PAINT MONO (3760 5160);
FORCEPROP 0 LASTPIN (3750 4300) $PN 1
J 0
(3760 4310);
DISPLAY 0.489362 (3760 4310);
PAINT MONO (3760 4310);
FORCEPROP 2 LAST PART_TYPE SMLF
J 0
(3050 5575);
DISPLAY 0.638298 (3050 5575);
FORCEPROP 1 LAST MATERIAL IC
J 0
(3050 5275);
DISPLAY 0.489362 (3050 5275);
PAINT SKYBLUE (3050 5275);
FORCEPROP 2 LAST VALUE ISL99390FRZ-TR5935
J 0
(3050 5525);
DISPLAY 0.489362 (3050 5525);
PAINT SKYBLUE (3050 5525);
FORCEPROP 1 LAST PART_NUMBER AL099390004
J 0
(3050 5350);
DISPLAY 0.489362 (3050 5350);
PAINT SKYBLUE (3050 5350);
FORCEPROP 2 LAST CDS_LIB pure_quanta
J 0
(3350 4550);
DISPLAY INVISIBLE (3350 4550);
FORCEPROP 1 LAST CDS_LMAN_SYM_OUTLINE -300,700,250,-650
J 0
(3350 4550);
DISPLAY 0.468085 (3350 4550);
PAINT GREEN (3350 4550);
DISPLAY INVISIBLE (3350 4550);
FORCEPROP 1 LAST NEEDS_NO_SIZE TRUE
J 0
(3350 4550);
DISPLAY 0.723404 (3350 4550);
PAINT GREEN (3350 4550);
DISPLAY INVISIBLE (3350 4550);
FORCEPROP 1 LAST PATH I31
J 0
(3350 4550);
DISPLAY 0.723404 (3350 4550);
PAINT GREEN (3350 4550);
DISPLAY INVISIBLE (3350 4550);
FORCEADD UNIVERSAL_GND..1
(4000 3825);
FORCEPROP 3 LASTPIN (4000 3875) SIG_NAME GND\g
J 0
(4010 3885);
DISPLAY 0.659574 (4010 3885);
PAINT MONO (4010 3885);
DISPLAY INVISIBLE (4010 3885);
FORCEPROP 2 LAST CDS_LIB pure_quanta_power
J 0
(4000 3825);
PAINT MONO (4000 3825);
DISPLAY INVISIBLE (4000 3825);
FORCEPROP 1 LAST PATH I36
J 0
(4075 3825);
DISPLAY 0.872340 (4075 3825);
PAINT AQUA (4075 3825);
DISPLAY INVISIBLE (4075 3825);
FORCEPROP 1 LAST HDL_POWER GND
J 1
(4025 3750);
DISPLAY 0.872340 (4025 3750);
PAINT GREEN (4025 3750);
DISPLAY INVISIBLE (4025 3750);
FORCEADD Q_CAP..1
(4625 5450);
FORCEPROP 1 LAST LOCATION PC135_5
J 0
(4675 5600);
DISPLAY 0.489362 (4675 5600);
PAINT SKYBLUE (4675 5600);
FORCEPROP 0 LAST $SEC 1
J 0
(4675 5650);
DISPLAY 0.680851 (4675 5650);
PAINT MONO (4675 5650);
DISPLAY INVISIBLE (4675 5650);
FORCEPROP 0 LAST CDS_SEC 1
J 0
(4675 5650);
DISPLAY 1.021277 (4675 5650);
DISPLAY INVISIBLE (4675 5650);
FORCEPROP 1 LASTPIN (4625 5550) $PN 1
J 0
(4635 5530);
DISPLAY 0.489362 (4635 5530);
PAINT MONO (4635 5530);
FORCEPROP 1 LASTPIN (4625 5350) $PN 2
J 0
(4635 5330);
DISPLAY 0.489362 (4635 5330);
PAINT MONO (4635 5330);
FORCEPROP 1 LAST MATERIAL X6S
J 0
(4675 5400);
DISPLAY 0.489362 (4675 5400);
PAINT SKYBLUE (4675 5400);
FORCEPROP 1 LAST TOLERANCE 10%
J 0
(4675 5450);
DISPLAY 0.489362 (4675 5450);
PAINT SKYBLUE (4675 5450);
FORCEPROP 1 LAST VALUE 1UF
J 0
(4675 5550);
DISPLAY 0.489362 (4675 5550);
PAINT SKYBLUE (4675 5550);
FORCEPROP 1 LAST PART_NUMBER CH5104KEB02
J 0
(4675 5300);
DISPLAY 0.489362 (4675 5300);
PAINT SKYBLUE (4675 5300);
FORCEPROP 1 LAST VOLTAGE 25V
J 0
(4675 5500);
DISPLAY 0.489362 (4675 5500);
PAINT SKYBLUE (4675 5500);
FORCEPROP 1 LAST PACK_TYPE C0402
J 0
(4675 5350);
DISPLAY 0.489362 (4675 5350);
PAINT SKYBLUE (4675 5350);
FORCEPROP 2 LAST CDS_LIB pure_quanta
J 0
(4625 5450);
DISPLAY INVISIBLE (4625 5450);
FORCEPROP 1 LAST PATH I39
J 0
(4675 5600);
DISPLAY 0.978723 (4675 5600);
PAINT WHITE (4675 5600);
DISPLAY INVISIBLE (4675 5600);
FORCEADD Q_CAP..1
(5025 5450);
FORCEPROP 1 LAST LOCATION PC136_5
J 0
(5075 5600);
DISPLAY 0.489362 (5075 5600);
PAINT SKYBLUE (5075 5600);
FORCEPROP 0 LAST $SEC 1
J 0
(5075 5650);
DISPLAY 0.680851 (5075 5650);
PAINT MONO (5075 5650);
DISPLAY INVISIBLE (5075 5650);
FORCEPROP 0 LAST CDS_SEC 1
J 0
(5075 5650);
DISPLAY 1.021277 (5075 5650);
DISPLAY INVISIBLE (5075 5650);
FORCEPROP 1 LASTPIN (5025 5550) $PN 1
J 0
(5035 5530);
DISPLAY 0.489362 (5035 5530);
PAINT MONO (5035 5530);
FORCEPROP 1 LASTPIN (5025 5350) $PN 2
J 0
(5035 5330);
DISPLAY 0.489362 (5035 5330);
PAINT MONO (5035 5330);
FORCEPROP 1 LAST MATERIAL X6S
J 0
(5075 5400);
DISPLAY 0.489362 (5075 5400);
PAINT SKYBLUE (5075 5400);
FORCEPROP 1 LAST TOLERANCE 10%
J 0
(5075 5450);
DISPLAY 0.489362 (5075 5450);
PAINT SKYBLUE (5075 5450);
FORCEPROP 1 LAST VALUE 10UF
J 0
(5075 5550);
DISPLAY 0.489362 (5075 5550);
PAINT SKYBLUE (5075 5550);
FORCEPROP 1 LAST VOLTAGE 25V
J 0
(5075 5500);
DISPLAY 0.489362 (5075 5500);
PAINT SKYBLUE (5075 5500);
FORCEPROP 1 LAST PACK_TYPE C0805
J 0
(5075 5350);
DISPLAY 0.489362 (5075 5350);
PAINT SKYBLUE (5075 5350);
FORCEPROP 1 LAST PART_NUMBER CH6104KEA00
J 0
(5075 5300);
DISPLAY 0.489362 (5075 5300);
PAINT SKYBLUE (5075 5300);
FORCEPROP 2 LAST CDS_LIB pure_quanta
J 0
(5025 5450);
DISPLAY INVISIBLE (5025 5450);
FORCEPROP 1 LAST PATH I40
J 0
(5075 5600);
DISPLAY 0.978723 (5075 5600);
PAINT WHITE (5075 5600);
DISPLAY INVISIBLE (5075 5600);
FORCEADD UNIVERSAL_GND..1
(5800 5100);
FORCEPROP 3 LASTPIN (5800 5150) SIG_NAME GND\g
J 0
(5810 5160);
DISPLAY 0.659574 (5810 5160);
PAINT MONO (5810 5160);
DISPLAY INVISIBLE (5810 5160);
FORCEPROP 2 LAST CDS_LIB pure_quanta_power
J 0
(5800 5100);
PAINT MONO (5800 5100);
DISPLAY INVISIBLE (5800 5100);
FORCEPROP 1 LAST PATH I54
J 0
(5875 5100);
DISPLAY 0.872340 (5875 5100);
PAINT AQUA (5875 5100);
DISPLAY INVISIBLE (5875 5100);
FORCEPROP 1 LAST HDL_POWER GND
J 1
(5825 5025);
DISPLAY 0.872340 (5825 5025);
PAINT GREEN (5825 5025);
DISPLAY INVISIBLE (5825 5025);
FORCEADD Q_CAP..1
(5425 5450);
FORCEPROP 1 LAST LOCATION PC138_5
J 0
(5475 5600);
DISPLAY 0.489362 (5475 5600);
PAINT SKYBLUE (5475 5600);
FORCEPROP 0 LAST $SEC 1
J 0
(5475 5650);
DISPLAY 0.680851 (5475 5650);
PAINT MONO (5475 5650);
DISPLAY INVISIBLE (5475 5650);
FORCEPROP 0 LAST CDS_SEC 1
J 0
(5475 5650);
DISPLAY 1.021277 (5475 5650);
DISPLAY INVISIBLE (5475 5650);
FORCEPROP 1 LASTPIN (5425 5550) $PN 1
J 0
(5435 5530);
DISPLAY 0.489362 (5435 5530);
PAINT MONO (5435 5530);
FORCEPROP 1 LASTPIN (5425 5350) $PN 2
J 0
(5435 5330);
DISPLAY 0.489362 (5435 5330);
PAINT MONO (5435 5330);
FORCEPROP 1 LAST MATERIAL X6S
J 0
(5475 5400);
DISPLAY 0.489362 (5475 5400);
PAINT SKYBLUE (5475 5400);
FORCEPROP 1 LAST TOLERANCE 10%
J 0
(5475 5450);
DISPLAY 0.489362 (5475 5450);
PAINT SKYBLUE (5475 5450);
FORCEPROP 1 LAST VALUE 10UF
J 0
(5475 5550);
DISPLAY 0.489362 (5475 5550);
PAINT SKYBLUE (5475 5550);
FORCEPROP 1 LAST PART_NUMBER CH6104KEA00
J 0
(5475 5300);
DISPLAY 0.489362 (5475 5300);
PAINT SKYBLUE (5475 5300);
FORCEPROP 1 LAST VOLTAGE 25V
J 0
(5475 5500);
DISPLAY 0.489362 (5475 5500);
PAINT SKYBLUE (5475 5500);
FORCEPROP 1 LAST PACK_TYPE C0805
J 0
(5475 5350);
DISPLAY 0.489362 (5475 5350);
PAINT SKYBLUE (5475 5350);
FORCEPROP 2 LAST CDS_LIB pure_quanta
J 0
(5425 5450);
DISPLAY INVISIBLE (5425 5450);
FORCEPROP 1 LAST PATH I59
J 0
(5475 5600);
DISPLAY 0.978723 (5475 5600);
PAINT WHITE (5475 5600);
DISPLAY INVISIBLE (5475 5600);
FORCEADD Q_CAP..1
(5800 5450);
FORCEPROP 1 LAST LOCATION PC139_5
J 0
(5850 5600);
DISPLAY 0.489362 (5850 5600);
PAINT SKYBLUE (5850 5600);
FORCEPROP 0 LAST $SEC 1
J 0
(5850 5650);
DISPLAY 0.680851 (5850 5650);
PAINT MONO (5850 5650);
DISPLAY INVISIBLE (5850 5650);
FORCEPROP 0 LAST CDS_SEC 1
J 0
(5850 5650);
DISPLAY 1.021277 (5850 5650);
DISPLAY INVISIBLE (5850 5650);
FORCEPROP 1 LASTPIN (5800 5550) $PN 1
J 0
(5810 5530);
DISPLAY 0.489362 (5810 5530);
PAINT MONO (5810 5530);
FORCEPROP 1 LASTPIN (5800 5350) $PN 2
J 0
(5810 5330);
DISPLAY 0.489362 (5810 5330);
PAINT MONO (5810 5330);
FORCEPROP 1 LAST MATERIAL X6S
J 0
(5850 5400);
DISPLAY 0.489362 (5850 5400);
PAINT SKYBLUE (5850 5400);
FORCEPROP 1 LAST TOLERANCE 10%
J 0
(5850 5450);
DISPLAY 0.489362 (5850 5450);
PAINT SKYBLUE (5850 5450);
FORCEPROP 1 LAST VALUE 10UF
J 0
(5850 5550);
DISPLAY 0.489362 (5850 5550);
PAINT SKYBLUE (5850 5550);
FORCEPROP 1 LAST PART_NUMBER CH6104KEA00
J 0
(5850 5300);
DISPLAY 0.489362 (5850 5300);
PAINT SKYBLUE (5850 5300);
FORCEPROP 1 LAST VOLTAGE 25V
J 0
(5850 5500);
DISPLAY 0.489362 (5850 5500);
PAINT SKYBLUE (5850 5500);
FORCEPROP 1 LAST PACK_TYPE C0805
J 0
(5850 5350);
DISPLAY 0.489362 (5850 5350);
PAINT SKYBLUE (5850 5350);
FORCEPROP 2 LAST CDS_LIB pure_quanta
J 0
(5800 5450);
DISPLAY INVISIBLE (5800 5450);
FORCEPROP 1 LAST PATH I60
J 0
(5850 5600);
DISPLAY 0.978723 (5850 5600);
PAINT WHITE (5850 5600);
DISPLAY INVISIBLE (5850 5600);
FORCEADD VCC_CORE..1
(5800 5800);
FORCEPROP 3 LASTPIN (5800 5750) SIG_NAME SW_P12V_STBY_PVDDCR_CPU1_P0_FLT\g
J 0
(5810 5760);
DISPLAY 0.659574 (5810 5760);
PAINT MONO (5810 5760);
DISPLAY INVISIBLE (5810 5760);
FORCEPROP 1 LAST HDL_POWER SW_P12V_STBY_PVDDCR_CPU1_P0_FLT
J 1
(5800 5850);
DISPLAY 0.489362 (5800 5850);
PAINT GREEN (5800 5850);
FORCEPROP 2 LAST CDS_LIB pure_quanta_power
J 0
(5800 5800);
DISPLAY INVISIBLE (5800 5800);
FORCEPROP 1 LAST PATH I61
J 0
(5850 5825);
DISPLAY 0.872340 (5850 5825);
PAINT AQUA (5850 5825);
DISPLAY INVISIBLE (5850 5825);
FORCEADD OFFPAGE..3
(7125 4300);
FORCEPROP 2 LAST $XR0 177 
J 0
(7369 4300);
DISPLAY 0.638298 (7369 4300);
PAINT MONO (7369 4300);
FORCEPROP 1 LAST COMMENT_BODY TRUE
J 0
(7075 4200);
DISPLAY 0.872340 (7075 4200);
PAINT GREEN (7075 4200);
DISPLAY INVISIBLE (7075 4200);
FORCEPROP 1 LAST OFFPAGE TRUE
J 0
(7450 4175);
DISPLAY 0.872340 (7450 4175);
PAINT GREEN (7450 4175);
DISPLAY INVISIBLE (7450 4175);
FORCEPROP 2 LAST PATH I73
J 0
(7325 4375);
DISPLAY 1.021277 (7325 4375);
DISPLAY INVISIBLE (7325 4375);
FORCEPROP 2 LAST CDS_LIB standard
J 0
(7125 4300);
DISPLAY INVISIBLE (7125 4300);
FORCEADD OFFPAGE..6
(5325 4300);
FORCEPROP 2 LAST $XR0 179 
J 0
(5045 4300);
DISPLAY 0.638298 (5045 4300);
PAINT MONO (5045 4300);
FORCEPROP 2 LAST CDS_LIB standard
J 0
(5325 4300);
DISPLAY INVISIBLE (5325 4300);
FORCEPROP 1 LAST OFFPAGE TRUE
J 0
(5650 4175);
DISPLAY 0.872340 (5650 4175);
PAINT GREEN (5650 4175);
DISPLAY INVISIBLE (5650 4175);
FORCEPROP 1 LAST COMMENT_BODY TRUE
J 0
(5425 4225);
DISPLAY 0.872340 (5425 4225);
PAINT GREEN (5425 4225);
DISPLAY INVISIBLE (5425 4225);
FORCEPROP 2 LAST PATH I75
J 0
(5375 4375);
DISPLAY 1.021277 (5375 4375);
DISPLAY INVISIBLE (5375 4375);
FORCEADD Q_RES..1
(6000 3475);
FORCEPROP 1 LAST LOCATION PR96
J 0
(5975 3500);
DISPLAY 0.489362 (5975 3500);
PAINT SKYBLUE (5975 3500);
FORCEPROP 0 LAST $SEC 1
J 0
(6250 3625);
DISPLAY 0.680851 (6250 3625);
PAINT MONO (6250 3625);
DISPLAY INVISIBLE (6250 3625);
FORCEPROP 0 LAST CDS_SEC 1
J 0
(6250 3625);
DISPLAY 1.021277 (6250 3625);
DISPLAY INVISIBLE (6250 3625);
FORCEPROP 1 LASTPIN (5900 3475) $PN 1
J 0
(5912 3487);
DISPLAY 0.489362 (5912 3487);
PAINT MONO (5912 3487);
FORCEPROP 1 LASTPIN (6100 3475) $PN 2
J 0
(6062 3487);
DISPLAY 0.489362 (6062 3487);
PAINT MONO (6062 3487);
FORCEPROP 1 LAST PART_NUMBER CS00002JB38
J 0
(5700 3425);
DISPLAY 0.489362 (5700 3425);
PAINT SKYBLUE (5700 3425);
FORCEPROP 1 LAST WATTAGE 1/16W
J 2
(6250 3500);
DISPLAY 0.489362 (6250 3500);
PAINT SKYBLUE (6250 3500);
FORCEPROP 1 LAST MATERIAL CHIP
J 0
(6100 3375);
DISPLAY 0.489362 (6100 3375);
PAINT SKYBLUE (6100 3375);
FORCEPROP 1 LAST TOLERANCE 5%
J 0
(5850 3500);
DISPLAY 0.489362 (5850 3500);
PAINT SKYBLUE (5850 3500);
FORCEPROP 1 LAST VALUE 0
J 2
(5775 3500);
DISPLAY 0.489362 (5775 3500);
PAINT SKYBLUE (5775 3500);
FORCEPROP 1 LAST PACK_TYPE 0402LF
J 0
(6075 3425);
DISPLAY 0.489362 (6075 3425);
PAINT SKYBLUE (6075 3425);
FORCEPROP 2 LAST CDS_LIB pure_quanta
J 0
(6000 3475);
DISPLAY INVISIBLE (6000 3475);
FORCEPROP 1 LAST PATH I76
J 0
(5950 3625);
DISPLAY 0.978723 (5950 3625);
PAINT WHITE (5950 3625);
DISPLAY INVISIBLE (5950 3625);
FORCEADD VCC_CORE..1
(8075 4700);
FORCEPROP 3 LASTPIN (8075 4650) SIG_NAME PVDDCR_CPU1_P0\g
J 0
(8085 4660);
DISPLAY 0.659574 (8085 4660);
PAINT MONO (8085 4660);
DISPLAY INVISIBLE (8085 4660);
FORCEPROP 1 LAST HDL_POWER PVDDCR_CPU1_P0
J 1
(8075 4750);
DISPLAY 0.489362 (8075 4750);
PAINT GREEN (8075 4750);
FORCEPROP 2 LAST CDS_LIB pure_quanta_power
J 0
(8075 4700);
DISPLAY INVISIBLE (8075 4700);
FORCEPROP 1 LAST PATH I77
J 0
(8125 4725);
DISPLAY 0.872340 (8125 4725);
PAINT AQUA (8125 4725);
DISPLAY INVISIBLE (8125 4725);
FORCEADD UNIVERSAL_GND..1
(8075 4000);
FORCEPROP 3 LASTPIN (8075 4050) SIG_NAME GND\g
J 0
(8085 4060);
DISPLAY 0.659574 (8085 4060);
PAINT MONO (8085 4060);
DISPLAY INVISIBLE (8085 4060);
FORCEPROP 2 LAST CDS_LIB pure_quanta_power
J 0
(8075 4000);
PAINT MONO (8075 4000);
DISPLAY INVISIBLE (8075 4000);
FORCEPROP 1 LAST PATH I78
J 0
(8150 4000);
DISPLAY 0.872340 (8150 4000);
PAINT AQUA (8150 4000);
DISPLAY INVISIBLE (8150 4000);
FORCEPROP 1 LAST HDL_POWER GND
J 1
(8100 3925);
DISPLAY 0.872340 (8100 3925);
PAINT GREEN (8100 3925);
DISPLAY INVISIBLE (8100 3925);
FORCEADD Q_CAP..1
(8075 4350);
FORCEPROP 1 LAST LOCATION PC141_5
J 0
(8125 4475);
DISPLAY 0.489362 (8125 4475);
PAINT SKYBLUE (8125 4475);
FORCEPROP 0 LAST $SEC 1
J 0
(8125 4525);
DISPLAY 0.680851 (8125 4525);
PAINT MONO (8125 4525);
DISPLAY INVISIBLE (8125 4525);
FORCEPROP 0 LAST CDS_SEC 1
J 0
(8125 4525);
DISPLAY 1.021277 (8125 4525);
DISPLAY INVISIBLE (8125 4525);
FORCEPROP 1 LASTPIN (8075 4450) $PN 1
J 0
(8085 4430);
DISPLAY 0.489362 (8085 4430);
PAINT MONO (8085 4430);
FORCEPROP 1 LASTPIN (8075 4250) $PN 2
J 0
(8085 4230);
DISPLAY 0.489362 (8085 4230);
PAINT MONO (8085 4230);
FORCEPROP 1 LAST MATERIAL X6S
J 0
(8125 4275);
DISPLAY 0.489362 (8125 4275);
PAINT SKYBLUE (8125 4275);
FORCEPROP 1 LAST TOLERANCE 20%
J 0
(8125 4325);
DISPLAY 0.489362 (8125 4325);
PAINT SKYBLUE (8125 4325);
FORCEPROP 1 LAST VALUE 22UF
J 0
(8125 4425);
DISPLAY 0.489362 (8125 4425);
PAINT SKYBLUE (8125 4425);
FORCEPROP 1 LAST PART_NUMBER TMP_QCH622KMEA01
J 0
(8125 4175);
DISPLAY 0.489362 (8125 4175);
PAINT SKYBLUE (8125 4175);
FORCEPROP 1 LAST VOLTAGE 4V
J 0
(8125 4375);
DISPLAY 0.489362 (8125 4375);
PAINT SKYBLUE (8125 4375);
FORCEPROP 1 LAST PACK_TYPE 0805
J 0
(8125 4225);
DISPLAY 0.489362 (8125 4225);
PAINT SKYBLUE (8125 4225);
FORCEPROP 2 LAST CDS_LIB pure_quanta
J 0
(8075 4350);
DISPLAY INVISIBLE (8075 4350);
FORCEPROP 1 LAST PATH I79
J 0
(8125 4500);
DISPLAY 0.978723 (8125 4500);
PAINT WHITE (8125 4500);
DISPLAY INVISIBLE (8125 4500);
FORCEADD Q_CAP..1
(7650 4350);
FORCEPROP 1 LAST LOCATION PC140_5
J 0
(7700 4475);
DISPLAY 0.489362 (7700 4475);
PAINT SKYBLUE (7700 4475);
FORCEPROP 0 LAST $SEC 1
J 0
(7700 4525);
DISPLAY 0.680851 (7700 4525);
PAINT MONO (7700 4525);
DISPLAY INVISIBLE (7700 4525);
FORCEPROP 0 LAST CDS_SEC 1
J 0
(7700 4525);
DISPLAY 1.021277 (7700 4525);
DISPLAY INVISIBLE (7700 4525);
FORCEPROP 1 LASTPIN (7650 4450) $PN 1
J 0
(7660 4430);
DISPLAY 0.489362 (7660 4430);
PAINT MONO (7660 4430);
FORCEPROP 1 LASTPIN (7650 4250) $PN 2
J 0
(7660 4230);
DISPLAY 0.489362 (7660 4230);
PAINT MONO (7660 4230);
FORCEPROP 1 LAST MATERIAL X6S
J 0
(7700 4275);
DISPLAY 0.489362 (7700 4275);
PAINT SKYBLUE (7700 4275);
FORCEPROP 1 LAST TOLERANCE 20%
J 0
(7700 4325);
DISPLAY 0.489362 (7700 4325);
PAINT SKYBLUE (7700 4325);
FORCEPROP 1 LAST VALUE 22UF
J 0
(7700 4425);
DISPLAY 0.489362 (7700 4425);
PAINT SKYBLUE (7700 4425);
FORCEPROP 1 LAST PART_NUMBER TMP_QCH622KMEA01
J 0
(7700 4175);
DISPLAY 0.489362 (7700 4175);
PAINT SKYBLUE (7700 4175);
FORCEPROP 1 LAST VOLTAGE 4V
J 0
(7700 4375);
DISPLAY 0.489362 (7700 4375);
PAINT SKYBLUE (7700 4375);
FORCEPROP 1 LAST PACK_TYPE 0805
J 0
(7700 4225);
DISPLAY 0.489362 (7700 4225);
PAINT SKYBLUE (7700 4225);
FORCEPROP 2 LAST CDS_LIB pure_quanta
J 0
(7650 4350);
DISPLAY INVISIBLE (7650 4350);
FORCEPROP 1 LAST PATH I80
J 0
(7700 4500);
DISPLAY 0.978723 (7700 4500);
PAINT WHITE (7700 4500);
DISPLAY INVISIBLE (7700 4500);
FORCEADD Q_INDUCTOR4P_14..1
(6250 4425);
FORCEPROP 1 LAST LOCATION PL15
J 0
(6050 4675);
DISPLAY 0.489362 (6050 4675);
PAINT SKYBLUE (6050 4675);
FORCEPROP 0 LAST $SEC 1
J 0
(6025 4725);
DISPLAY 0.680851 (6025 4725);
PAINT MONO (6025 4725);
DISPLAY INVISIBLE (6025 4725);
FORCEPROP 0 LAST CDS_SEC 1
J 0
(6025 4725);
DISPLAY 1.021277 (6025 4725);
DISPLAY INVISIBLE (6025 4725);
FORCEPROP 0 LASTPIN (5850 4550) $PN 1
J 2
(5840 4560);
DISPLAY 0.489362 (5840 4560);
PAINT MONO (5840 4560);
FORCEPROP 0 LASTPIN (5850 4300) $PN 2
J 2
(5840 4310);
DISPLAY 0.489362 (5840 4310);
PAINT MONO (5840 4310);
FORCEPROP 0 LASTPIN (6650 4300) $PN 3
J 0
(6660 4310);
DISPLAY 0.489362 (6660 4310);
PAINT MONO (6660 4310);
FORCEPROP 0 LASTPIN (6650 4550) $PN 4
J 0
(6660 4560);
DISPLAY 0.489362 (6660 4560);
PAINT MONO (6660 4560);
FORCEPROP 2 LAST PART_TYPE SMLF
J 0
(6175 4175);
DISPLAY 1.021277 (6175 4175);
FORCEPROP 1 LAST MATERIAL IND
J 0
(6050 4600);
DISPLAY 0.489362 (6050 4600);
PAINT SKYBLUE (6050 4600);
FORCEPROP 2 LAST VALUE 150NH
J 0
(6150 4600);
DISPLAY 0.489362 (6150 4600);
PAINT SKYBLUE (6150 4600);
FORCEPROP 1 LAST PART_NUMBER CV+15^0TZ04
J 0
(6300 4600);
DISPLAY 0.489362 (6300 4600);
PAINT SKYBLUE (6300 4600);
FORCEPROP 2 LAST CDS_LIB pure_quanta
J 0
(6250 4425);
DISPLAY INVISIBLE (6250 4425);
FORCEPROP 1 LAST NEEDS_NO_SIZE TRUE
J 0
(6250 4425);
DISPLAY 0.468085 (6250 4425);
PAINT GREEN (6250 4425);
DISPLAY INVISIBLE (6250 4425);
FORCEPROP 1 LAST PATH I82
J 0
(6450 4580);
DISPLAY 0.723404 (6450 4580);
PAINT GREEN (6450 4580);
DISPLAY INVISIBLE (6450 4580);
FORCEADD Q_CAP..1
(925 4175);
FORCEPROP 1 LAST LOCATION PC132_5
J 0
(975 4275);
DISPLAY 0.489362 (975 4275);
PAINT SKYBLUE (975 4275);
FORCEPROP 0 LAST $SEC 1
J 0
(975 4300);
DISPLAY 0.680851 (975 4300);
PAINT MONO (975 4300);
DISPLAY INVISIBLE (975 4300);
FORCEPROP 0 LAST CDS_SEC 1
J 0
(1175 4225);
DISPLAY 1.021277 (1175 4225);
DISPLAY INVISIBLE (1175 4225);
FORCEPROP 1 LASTPIN (925 4275) $PN 1
J 0
(935 4255);
DISPLAY 0.489362 (935 4255);
PAINT MONO (935 4255);
FORCEPROP 1 LASTPIN (925 4075) $PN 2
J 0
(935 4055);
DISPLAY 0.489362 (935 4055);
PAINT MONO (935 4055);
FORCEPROP 1 LAST MATERIAL X7R
J 0
(975 4075);
DISPLAY 0.489362 (975 4075);
PAINT SKYBLUE (975 4075);
FORCEPROP 1 LAST TOLERANCE 10%
J 0
(975 4125);
DISPLAY 0.489362 (975 4125);
PAINT SKYBLUE (975 4125);
FORCEPROP 1 LAST VALUE 0.1UF
J 0
(975 4225);
DISPLAY 0.489362 (975 4225);
PAINT SKYBLUE (975 4225);
FORCEPROP 1 LAST PART_NUMBER CH4104K1B00
J 0
(975 4025);
DISPLAY 0.489362 (975 4025);
PAINT SKYBLUE (975 4025);
FORCEPROP 1 LAST VOLTAGE 25V
J 0
(975 4175);
DISPLAY 0.489362 (975 4175);
PAINT SKYBLUE (975 4175);
FORCEPROP 1 LAST PACK_TYPE 0402
J 0
(975 3975);
DISPLAY 0.489362 (975 3975);
PAINT SKYBLUE (975 3975);
FORCEPROP 2 LAST CDS_LIB pure_quanta
J 0
(925 4175);
DISPLAY INVISIBLE (925 4175);
FORCEPROP 1 LAST PATH I83
J 0
(975 4325);
DISPLAY 0.978723 (975 4325);
PAINT WHITE (975 4325);
DISPLAY INVISIBLE (975 4325);
FORCEADD Q_CAP..1
(5325 4775);
FORCEPROP 1 LAST LOCATION PC137
J 0
(5375 4875);
DISPLAY 0.489362 (5375 4875);
PAINT SKYBLUE (5375 4875);
FORCEPROP 0 LAST $SEC 1
J 0
(5375 4925);
DISPLAY 0.680851 (5375 4925);
PAINT MONO (5375 4925);
DISPLAY INVISIBLE (5375 4925);
FORCEPROP 0 LAST CDS_SEC 1
J 2
(5375 4900);
DISPLAY 1.021277 (5375 4900);
DISPLAY INVISIBLE (5375 4900);
FORCEPROP 1 LASTPIN (5325 4875) $PN 1
J 0
(5335 4855);
DISPLAY 0.489362 (5335 4855);
PAINT MONO (5335 4855);
FORCEPROP 1 LASTPIN (5325 4675) $PN 2
J 0
(5335 4655);
DISPLAY 0.489362 (5335 4655);
PAINT MONO (5335 4655);
FORCEPROP 1 LAST PART_NUMBER CH4223K1B00
J 0
(5375 4625);
DISPLAY 0.489362 (5375 4625);
PAINT SKYBLUE (5375 4625);
FORCEPROP 1 LAST MATERIAL X7R
J 0
(5375 4675);
DISPLAY 0.489362 (5375 4675);
PAINT SKYBLUE (5375 4675);
FORCEPROP 1 LAST TOLERANCE 10%
J 0
(5375 4725);
DISPLAY 0.489362 (5375 4725);
PAINT SKYBLUE (5375 4725);
FORCEPROP 1 LAST VALUE 0.22UF
J 0
(5375 4825);
DISPLAY 0.489362 (5375 4825);
PAINT SKYBLUE (5375 4825);
FORCEPROP 1 LAST VOLTAGE 16V
J 0
(5375 4775);
DISPLAY 0.489362 (5375 4775);
PAINT SKYBLUE (5375 4775);
FORCEPROP 1 LAST PACK_TYPE 0402
J 0
(5375 4575);
DISPLAY 0.489362 (5375 4575);
PAINT SKYBLUE (5375 4575);
FORCEPROP 2 LAST CDS_LIB pure_quanta
J 2
(5325 4775);
DISPLAY INVISIBLE (5325 4775);
FORCEPROP 1 LAST PATH I84
J 0
(5375 4925);
DISPLAY 0.978723 (5375 4925);
PAINT WHITE (5375 4925);
DISPLAY INVISIBLE (5375 4925);
FORCEADD Q_RES..1
(4600 4900);
FORCEPROP 1 LAST LOCATION PR95
J 0
(4375 4975);
DISPLAY 0.489362 (4375 4975);
PAINT SKYBLUE (4375 4975);
FORCEPROP 0 LAST $SEC 1
J 0
(4875 5000);
DISPLAY 0.680851 (4875 5000);
PAINT MONO (4875 5000);
DISPLAY INVISIBLE (4875 5000);
FORCEPROP 0 LAST CDS_SEC 1
J 0
(4875 5000);
DISPLAY 1.021277 (4875 5000);
DISPLAY INVISIBLE (4875 5000);
FORCEPROP 1 LASTPIN (4500 4900) $PN 1
J 0
(4512 4912);
DISPLAY 0.787234 (4512 4912);
PAINT MONO (4512 4912);
DISPLAY INVISIBLE (4512 4912);
FORCEPROP 1 LASTPIN (4700 4900) $PN 2
J 0
(4662 4912);
DISPLAY 0.787234 (4662 4912);
PAINT MONO (4662 4912);
DISPLAY INVISIBLE (4662 4912);
FORCEPROP 1 LAST PACK_TYPE 0402LF
J 0
(5000 4825);
DISPLAY 0.489362 (5000 4825);
PAINT SKYBLUE (5000 4825);
FORCEPROP 1 LAST TOLERANCE 1%
J 0
(4600 4975);
DISPLAY 0.489362 (4600 4975);
PAINT SKYBLUE (4600 4975);
FORCEPROP 1 LAST MATERIAL CHIP
J 0
(4450 4825);
DISPLAY 0.489362 (4450 4825);
PAINT SKYBLUE (4450 4825);
FORCEPROP 1 LAST WATTAGE 1/16W
J 2
(4875 4975);
DISPLAY 0.489362 (4875 4975);
PAINT SKYBLUE (4875 4975);
FORCEPROP 1 LAST VALUE 4.7
J 2
(4550 4975);
DISPLAY 0.489362 (4550 4975);
PAINT SKYBLUE (4550 4975);
FORCEPROP 1 LAST PART_NUMBER CS-4702FB19
J 0
(4625 4825);
DISPLAY 0.489362 (4625 4825);
PAINT SKYBLUE (4625 4825);
FORCEPROP 1 LAST PATH I85
J 0
(4550 5050);
DISPLAY 0.978723 (4550 5050);
PAINT WHITE (4550 5050);
DISPLAY INVISIBLE (4550 5050);
FORCEPROP 2 LAST CDS_LIB pure_quanta
J 0
(4600 4900);
DISPLAY INVISIBLE (4600 4900);
FORCEADD Q_CAP..1
(4200 5450);
FORCEPROP 1 LAST LOCATION PC134_5
J 0
(4250 5600);
DISPLAY 0.489362 (4250 5600);
PAINT SKYBLUE (4250 5600);
FORCEPROP 0 LAST $SEC 1
J 0
(4250 5600);
DISPLAY 0.680851 (4250 5600);
PAINT MONO (4250 5600);
DISPLAY INVISIBLE (4250 5600);
FORCEPROP 0 LAST CDS_SEC 1
J 0
(4250 5600);
DISPLAY 1.021277 (4250 5600);
DISPLAY INVISIBLE (4250 5600);
FORCEPROP 1 LASTPIN (4200 5550) $PN 1
J 0
(4210 5530);
DISPLAY 0.489362 (4210 5530);
PAINT MONO (4210 5530);
FORCEPROP 1 LASTPIN (4200 5350) $PN 2
J 0
(4210 5330);
DISPLAY 0.489362 (4210 5330);
PAINT MONO (4210 5330);
FORCEPROP 1 LAST MATERIAL X7R
J 0
(4250 5400);
DISPLAY 0.489362 (4250 5400);
PAINT SKYBLUE (4250 5400);
FORCEPROP 1 LAST TOLERANCE 10%
J 0
(4250 5450);
DISPLAY 0.489362 (4250 5450);
PAINT SKYBLUE (4250 5450);
FORCEPROP 1 LAST VALUE 0.1UF
J 0
(4250 5550);
DISPLAY 0.489362 (4250 5550);
PAINT SKYBLUE (4250 5550);
FORCEPROP 1 LAST PART_NUMBER CH4104K1B00
J 0
(4250 5350);
DISPLAY 0.489362 (4250 5350);
PAINT SKYBLUE (4250 5350);
FORCEPROP 1 LAST VOLTAGE 25V
J 0
(4250 5500);
DISPLAY 0.489362 (4250 5500);
PAINT SKYBLUE (4250 5500);
FORCEPROP 1 LAST PACK_TYPE 0402
J 0
(4250 5300);
DISPLAY 0.489362 (4250 5300);
PAINT SKYBLUE (4250 5300);
FORCEPROP 2 LAST CDS_LIB pure_quanta
J 0
(4200 5450);
DISPLAY INVISIBLE (4200 5450);
FORCEPROP 1 LAST PATH I86
J 0
(4250 5600);
DISPLAY 0.978723 (4250 5600);
PAINT WHITE (4250 5600);
DISPLAY INVISIBLE (4250 5600);
FORCEADD Q_CAP..1
(1875 4975);
FORCEPROP 1 LAST LOCATION PC131
J 0
(1925 5075);
DISPLAY 0.489362 (1925 5075);
PAINT SKYBLUE (1925 5075);
FORCEPROP 0 LAST $SEC 1
J 0
(1925 5125);
DISPLAY 0.680851 (1925 5125);
PAINT MONO (1925 5125);
DISPLAY INVISIBLE (1925 5125);
FORCEPROP 0 LAST CDS_SEC 1
J 0
(1925 5125);
DISPLAY 1.021277 (1925 5125);
DISPLAY INVISIBLE (1925 5125);
FORCEPROP 1 LASTPIN (1875 5075) $PN 1
J 0
(1885 5055);
DISPLAY 0.489362 (1885 5055);
PAINT MONO (1885 5055);
FORCEPROP 1 LASTPIN (1875 4875) $PN 2
J 0
(1885 4855);
DISPLAY 0.489362 (1885 4855);
PAINT MONO (1885 4855);
FORCEPROP 1 LAST MATERIAL X6S
J 0
(1925 4875);
DISPLAY 0.489362 (1925 4875);
PAINT SKYBLUE (1925 4875);
FORCEPROP 1 LAST TOLERANCE 10%
J 0
(1925 4925);
DISPLAY 0.489362 (1925 4925);
PAINT SKYBLUE (1925 4925);
FORCEPROP 1 LAST VALUE 2.2UF
J 0
(1925 5025);
DISPLAY 0.489362 (1925 5025);
PAINT SKYBLUE (1925 5025);
FORCEPROP 1 LAST PART_NUMBER CH5222KEB01
J 0
(1925 4825);
DISPLAY 0.489362 (1925 4825);
PAINT SKYBLUE (1925 4825);
FORCEPROP 1 LAST VOLTAGE 10V
J 0
(1925 4975);
DISPLAY 0.489362 (1925 4975);
PAINT SKYBLUE (1925 4975);
FORCEPROP 1 LAST PACK_TYPE C0402
J 0
(1925 4775);
DISPLAY 0.489362 (1925 4775);
PAINT SKYBLUE (1925 4775);
FORCEPROP 2 LAST CDS_LIB pure_quanta
J 0
(1875 4975);
DISPLAY INVISIBLE (1875 4975);
FORCEPROP 1 LAST PATH I87
J 0
(1925 5125);
DISPLAY 0.978723 (1925 5125);
PAINT WHITE (1925 5125);
DISPLAY INVISIBLE (1925 5125);
FORCEADD UNIVERSAL_GND..1
(1875 4775);
FORCEPROP 3 LASTPIN (1875 4825) SIG_NAME GND\g
J 0
(1885 4835);
DISPLAY 0.659574 (1885 4835);
PAINT MONO (1885 4835);
DISPLAY INVISIBLE (1885 4835);
FORCEPROP 2 LAST CDS_LIB pure_quanta_power
J 0
(1875 4775);
DISPLAY INVISIBLE (1875 4775);
FORCEPROP 1 LAST PATH I88
J 0
(1950 4775);
DISPLAY 0.872340 (1950 4775);
PAINT AQUA (1950 4775);
DISPLAY INVISIBLE (1950 4775);
FORCEPROP 1 LAST HDL_POWER GND
J 1
(1900 4700);
DISPLAY 0.872340 (1900 4700);
PAINT GREEN (1900 4700);
DISPLAY INVISIBLE (1900 4700);
FORCEADD UNIVERSAL_GND..1
(2225 5275);
FORCEPROP 3 LASTPIN (2225 5325) SIG_NAME GND\g
J 0
(2235 5335);
DISPLAY 0.659574 (2235 5335);
PAINT MONO (2235 5335);
DISPLAY INVISIBLE (2235 5335);
FORCEPROP 2 LAST CDS_LIB pure_quanta_power
J 0
(2225 5275);
DISPLAY INVISIBLE (2225 5275);
FORCEPROP 1 LAST PATH I89
J 0
(2300 5275);
DISPLAY 0.872340 (2300 5275);
PAINT AQUA (2300 5275);
DISPLAY INVISIBLE (2300 5275);
FORCEPROP 1 LAST HDL_POWER GND
J 1
(2250 5200);
DISPLAY 0.872340 (2250 5200);
PAINT GREEN (2250 5200);
DISPLAY INVISIBLE (2250 5200);
FORCEADD Q_RES..2
(1875 5525);
FORCEPROP 1 LAST LOCATION PR94
J 0
(1920 5650);
DISPLAY 0.489362 (1920 5650);
PAINT SKYBLUE (1920 5650);
FORCEPROP 0 LAST $SEC 1
J 0
(1925 5700);
DISPLAY 0.680851 (1925 5700);
PAINT MONO (1925 5700);
DISPLAY INVISIBLE (1925 5700);
FORCEPROP 0 LAST CDS_SEC 1
J 0
(1925 5700);
DISPLAY 1.021277 (1925 5700);
DISPLAY INVISIBLE (1925 5700);
FORCEPROP 1 LASTPIN (1875 5625) $PN 1
J 0
(1880 5587);
DISPLAY 0.489362 (1880 5587);
PAINT MONO (1880 5587);
FORCEPROP 1 LASTPIN (1875 5425) $PN 2
J 0
(1880 5435);
DISPLAY 0.489362 (1880 5435);
PAINT MONO (1880 5435);
FORCEPROP 1 LAST WATTAGE 1/16W
J 0
(1925 5500);
DISPLAY 0.489362 (1925 5500);
PAINT SKYBLUE (1925 5500);
FORCEPROP 1 LAST MATERIAL CHIP
J 0
(1925 5450);
DISPLAY 0.489362 (1925 5450);
PAINT SKYBLUE (1925 5450);
FORCEPROP 1 LAST TOLERANCE 1%
J 0
(1925 5550);
DISPLAY 0.489362 (1925 5550);
PAINT SKYBLUE (1925 5550);
FORCEPROP 1 LAST VALUE 2.2
J 0
(1925 5600);
DISPLAY 0.489362 (1925 5600);
PAINT SKYBLUE (1925 5600);
FORCEPROP 1 LAST PART_NUMBER CS-2202FB00
J 0
(1925 5400);
DISPLAY 0.489362 (1925 5400);
PAINT SKYBLUE (1925 5400);
FORCEPROP 1 LAST PACK_TYPE 0402LF
J 0
(1925 5350);
DISPLAY 0.489362 (1925 5350);
PAINT SKYBLUE (1925 5350);
FORCEPROP 2 LAST CDS_LIB pure_quanta
J 0
(1875 5525);
DISPLAY INVISIBLE (1875 5525);
FORCEPROP 1 LAST PATH I90
J 0
(1925 5700);
DISPLAY 0.978723 (1925 5700);
PAINT WHITE (1925 5700);
DISPLAY INVISIBLE (1925 5700);
FORCEADD Q_CAP..1
(2225 5550);
FORCEPROP 1 LAST LOCATION PC133_C1P0_5
J 0
(2275 5650);
DISPLAY 0.489362 (2275 5650);
PAINT SKYBLUE (2275 5650);
FORCEPROP 0 LAST $SEC 1
J 0
(2275 5700);
DISPLAY 0.680851 (2275 5700);
PAINT MONO (2275 5700);
DISPLAY INVISIBLE (2275 5700);
FORCEPROP 0 LAST CDS_SEC 1
J 0
(2275 5700);
DISPLAY 1.021277 (2275 5700);
DISPLAY INVISIBLE (2275 5700);
FORCEPROP 1 LASTPIN (2225 5650) $PN 1
J 0
(2235 5630);
DISPLAY 0.489362 (2235 5630);
PAINT MONO (2235 5630);
FORCEPROP 1 LASTPIN (2225 5450) $PN 2
J 0
(2235 5430);
DISPLAY 0.489362 (2235 5430);
PAINT MONO (2235 5430);
FORCEPROP 1 LAST MATERIAL X6S
J 0
(2275 5450);
DISPLAY 0.489362 (2275 5450);
PAINT SKYBLUE (2275 5450);
FORCEPROP 1 LAST TOLERANCE 10%
J 0
(2275 5500);
DISPLAY 0.489362 (2275 5500);
PAINT SKYBLUE (2275 5500);
FORCEPROP 1 LAST VALUE 2.2UF
J 0
(2275 5600);
DISPLAY 0.489362 (2275 5600);
PAINT SKYBLUE (2275 5600);
FORCEPROP 1 LAST PART_NUMBER CH5222KEB01
J 0
(2275 5400);
DISPLAY 0.489362 (2275 5400);
PAINT SKYBLUE (2275 5400);
FORCEPROP 1 LAST VOLTAGE 10V
J 0
(2275 5550);
DISPLAY 0.489362 (2275 5550);
PAINT SKYBLUE (2275 5550);
FORCEPROP 1 LAST PACK_TYPE C0402
J 0
(2275 5350);
DISPLAY 0.489362 (2275 5350);
PAINT SKYBLUE (2275 5350);
FORCEPROP 2 LAST CDS_LIB pure_quanta
J 0
(2225 5550);
DISPLAY INVISIBLE (2225 5550);
FORCEPROP 1 LAST PATH I91
J 0
(2275 5700);
DISPLAY 0.978723 (2275 5700);
PAINT WHITE (2275 5700);
DISPLAY INVISIBLE (2275 5700);
FORCEADD UNIVERSAL_GND..1
(925 3975);
FORCEPROP 3 LASTPIN (925 4025) SIG_NAME GND\g
J 0
(935 4035);
DISPLAY 0.659574 (935 4035);
PAINT MONO (935 4035);
DISPLAY INVISIBLE (935 4035);
FORCEPROP 2 LAST CDS_LIB pure_quanta_power
J 0
(925 3975);
DISPLAY INVISIBLE (925 3975);
FORCEPROP 1 LAST PATH I93
J 0
(1000 3975);
DISPLAY 0.872340 (1000 3975);
PAINT AQUA (1000 3975);
DISPLAY INVISIBLE (1000 3975);
FORCEPROP 1 LAST HDL_POWER GND
J 1
(950 3900);
DISPLAY 0.872340 (950 3900);
PAINT GREEN (950 3900);
DISPLAY INVISIBLE (950 3900);
FORCEADD Q_INDUCTOR4P_14..1
(6250 1775);
FORCEPROP 1 LAST LOCATION PL7
J 0
(6050 2000);
DISPLAY 0.489362 (6050 2000);
PAINT SKYBLUE (6050 2000);
FORCEPROP 0 LAST $SEC 1
J 0
(6025 2075);
DISPLAY 0.680851 (6025 2075);
PAINT MONO (6025 2075);
DISPLAY INVISIBLE (6025 2075);
FORCEPROP 0 LAST CDS_SEC 1
J 0
(6025 2075);
DISPLAY 1.021277 (6025 2075);
DISPLAY INVISIBLE (6025 2075);
FORCEPROP 0 LASTPIN (5850 1900) $PN 1
J 2
(5840 1910);
DISPLAY 0.489362 (5840 1910);
PAINT MONO (5840 1910);
FORCEPROP 0 LASTPIN (5850 1650) $PN 2
J 2
(5840 1660);
DISPLAY 0.489362 (5840 1660);
PAINT MONO (5840 1660);
FORCEPROP 0 LASTPIN (6650 1650) $PN 3
J 0
(6660 1660);
DISPLAY 0.489362 (6660 1660);
PAINT MONO (6660 1660);
FORCEPROP 0 LASTPIN (6650 1900) $PN 4
J 0
(6660 1910);
DISPLAY 0.489362 (6660 1910);
PAINT MONO (6660 1910);
FORCEPROP 1 LAST MATERIAL IND
J 0
(6050 1950);
DISPLAY 0.489362 (6050 1950);
PAINT SKYBLUE (6050 1950);
FORCEPROP 2 LAST VALUE 150NH
J 0
(6150 1950);
DISPLAY 0.489362 (6150 1950);
PAINT SKYBLUE (6150 1950);
FORCEPROP 1 LAST PART_NUMBER CV+15^0TZ04
J 0
(6300 1950);
DISPLAY 0.489362 (6300 1950);
PAINT SKYBLUE (6300 1950);
FORCEPROP 2 LAST PART_TYPE SMLF
J 0
(6175 1525);
DISPLAY 1.021277 (6175 1525);
FORCEPROP 1 LAST NEEDS_NO_SIZE TRUE
J 0
(6250 1775);
DISPLAY 0.468085 (6250 1775);
PAINT GREEN (6250 1775);
DISPLAY INVISIBLE (6250 1775);
FORCEPROP 2 LAST CDS_LIB pure_quanta
J 0
(6250 1775);
DISPLAY INVISIBLE (6250 1775);
FORCEPROP 1 LAST PATH I94
J 0
(6450 1930);
DISPLAY 0.723404 (6450 1930);
PAINT GREEN (6450 1930);
DISPLAY INVISIBLE (6450 1930);
FORCEADD VCC_CORE..1
(8050 2050);
FORCEPROP 3 LASTPIN (8050 2000) SIG_NAME PVDDCR_CPU1_P0\g
J 0
(8060 2010);
DISPLAY 0.659574 (8060 2010);
PAINT MONO (8060 2010);
DISPLAY INVISIBLE (8060 2010);
FORCEPROP 1 LAST HDL_POWER PVDDCR_CPU1_P0
J 1
(8050 2100);
DISPLAY 0.489362 (8050 2100);
PAINT GREEN (8050 2100);
FORCEPROP 2 LAST CDS_LIB pure_quanta_power
J 0
(8050 2050);
DISPLAY INVISIBLE (8050 2050);
FORCEPROP 1 LAST PATH I95
J 0
(8100 2075);
DISPLAY 0.872340 (8100 2075);
PAINT AQUA (8100 2075);
DISPLAY INVISIBLE (8100 2075);
FORCEADD Q_CAP..1
(8050 1700);
FORCEPROP 1 LAST LOCATION PC123_6
J 0
(8100 1825);
DISPLAY 0.489362 (8100 1825);
PAINT SKYBLUE (8100 1825);
FORCEPROP 0 LAST $SEC 1
J 0
(8100 1875);
DISPLAY 0.680851 (8100 1875);
PAINT MONO (8100 1875);
DISPLAY INVISIBLE (8100 1875);
FORCEPROP 0 LAST CDS_SEC 1
J 0
(8100 1875);
DISPLAY 1.021277 (8100 1875);
DISPLAY INVISIBLE (8100 1875);
FORCEPROP 1 LASTPIN (8050 1800) $PN 1
J 0
(8060 1780);
DISPLAY 0.489362 (8060 1780);
PAINT MONO (8060 1780);
FORCEPROP 1 LASTPIN (8050 1600) $PN 2
J 0
(8060 1580);
DISPLAY 0.489362 (8060 1580);
PAINT MONO (8060 1580);
FORCEPROP 1 LAST MATERIAL X6S
J 0
(8100 1625);
DISPLAY 0.489362 (8100 1625);
PAINT SKYBLUE (8100 1625);
FORCEPROP 1 LAST TOLERANCE 20%
J 0
(8100 1675);
DISPLAY 0.489362 (8100 1675);
PAINT SKYBLUE (8100 1675);
FORCEPROP 1 LAST VALUE 22UF
J 0
(8100 1775);
DISPLAY 0.489362 (8100 1775);
PAINT SKYBLUE (8100 1775);
FORCEPROP 1 LAST PART_NUMBER TMP_QCH622KMEA01
J 0
(8100 1525);
DISPLAY 0.489362 (8100 1525);
PAINT SKYBLUE (8100 1525);
FORCEPROP 1 LAST VOLTAGE 4V
J 0
(8100 1725);
DISPLAY 0.489362 (8100 1725);
PAINT SKYBLUE (8100 1725);
FORCEPROP 1 LAST PACK_TYPE 0805
J 0
(8100 1575);
DISPLAY 0.489362 (8100 1575);
PAINT SKYBLUE (8100 1575);
FORCEPROP 2 LAST CDS_LIB pure_quanta
J 0
(8050 1700);
DISPLAY INVISIBLE (8050 1700);
FORCEPROP 1 LAST PATH I96
J 0
(8100 1850);
DISPLAY 0.978723 (8100 1850);
PAINT WHITE (8100 1850);
DISPLAY INVISIBLE (8100 1850);
FORCEADD Q_CAP..1
(7625 1700);
FORCEPROP 1 LAST LOCATION PC120_6
J 0
(7675 1825);
DISPLAY 0.489362 (7675 1825);
PAINT SKYBLUE (7675 1825);
FORCEPROP 0 LAST $SEC 1
J 0
(7675 1875);
DISPLAY 0.680851 (7675 1875);
PAINT MONO (7675 1875);
DISPLAY INVISIBLE (7675 1875);
FORCEPROP 0 LAST CDS_SEC 1
J 0
(7675 1875);
DISPLAY 1.021277 (7675 1875);
DISPLAY INVISIBLE (7675 1875);
FORCEPROP 1 LASTPIN (7625 1800) $PN 1
J 0
(7635 1780);
DISPLAY 0.489362 (7635 1780);
PAINT MONO (7635 1780);
FORCEPROP 1 LASTPIN (7625 1600) $PN 2
J 0
(7635 1580);
DISPLAY 0.489362 (7635 1580);
PAINT MONO (7635 1580);
FORCEPROP 1 LAST MATERIAL X6S
J 0
(7675 1625);
DISPLAY 0.489362 (7675 1625);
PAINT SKYBLUE (7675 1625);
FORCEPROP 1 LAST TOLERANCE 20%
J 0
(7675 1675);
DISPLAY 0.489362 (7675 1675);
PAINT SKYBLUE (7675 1675);
FORCEPROP 1 LAST VALUE 22UF
J 0
(7675 1775);
DISPLAY 0.489362 (7675 1775);
PAINT SKYBLUE (7675 1775);
FORCEPROP 1 LAST PART_NUMBER TMP_QCH622KMEA01
J 0
(7675 1525);
DISPLAY 0.489362 (7675 1525);
PAINT SKYBLUE (7675 1525);
FORCEPROP 1 LAST VOLTAGE 4V
J 0
(7675 1725);
DISPLAY 0.489362 (7675 1725);
PAINT SKYBLUE (7675 1725);
FORCEPROP 1 LAST PACK_TYPE 0805
J 0
(7675 1575);
DISPLAY 0.489362 (7675 1575);
PAINT SKYBLUE (7675 1575);
FORCEPROP 2 LAST CDS_LIB pure_quanta
J 0
(7625 1700);
DISPLAY INVISIBLE (7625 1700);
FORCEPROP 1 LAST PATH I97
J 0
(7675 1850);
DISPLAY 0.978723 (7675 1850);
PAINT WHITE (7675 1850);
DISPLAY INVISIBLE (7675 1850);
FORCEADD OFFPAGE..3
(7100 1650);
FORCEPROP 2 LAST $XR0 179 
J 0
(7344 1650);
DISPLAY 0.638298 (7344 1650);
PAINT MONO (7344 1650);
FORCEPROP 2 LAST CDS_LIB standard
J 0
(7100 1650);
DISPLAY INVISIBLE (7100 1650);
FORCEPROP 1 LAST OFFPAGE TRUE
J 0
(7425 1525);
DISPLAY 0.872340 (7425 1525);
PAINT GREEN (7425 1525);
DISPLAY INVISIBLE (7425 1525);
FORCEPROP 1 LAST COMMENT_BODY TRUE
J 0
(7050 1550);
DISPLAY 0.872340 (7050 1550);
PAINT GREEN (7050 1550);
DISPLAY INVISIBLE (7050 1550);
FORCEPROP 2 LAST PATH I98
J 0
(7350 1700);
DISPLAY 1.021277 (7350 1700);
DISPLAY INVISIBLE (7350 1700);
FORCEADD VCC_CORE..1
(5775 3150);
FORCEPROP 3 LASTPIN (5775 3100) SIG_NAME SW_P12V_STBY_PVDDCR_CPU1_P0_FLT\g
J 0
(5785 3110);
DISPLAY 0.659574 (5785 3110);
PAINT MONO (5785 3110);
DISPLAY INVISIBLE (5785 3110);
FORCEPROP 1 LAST HDL_POWER SW_P12V_STBY_PVDDCR_CPU1_P0_FLT
J 1
(5775 3200);
DISPLAY 0.489362 (5775 3200);
PAINT GREEN (5775 3200);
FORCEPROP 2 LAST CDS_LIB pure_quanta_power
J 0
(5775 3150);
DISPLAY INVISIBLE (5775 3150);
FORCEPROP 1 LAST PATH I99
J 0
(5825 3175);
DISPLAY 0.872340 (5825 3175);
PAINT AQUA (5825 3175);
DISPLAY INVISIBLE (5825 3175);
FORCEADD DNS..1
(1400 1375);
PAINT RED (1400 1375);
FORCEPROP 2 LAST CDS_LIB mstr_misc
J 0
(1400 1375);
PAINT MONO (1400 1375);
DISPLAY INVISIBLE (1400 1375);
FORCEPROP 1 LAST COMMENT_BODY TRUE
R 1
J 0
(1475 1150);
DISPLAY 0.872340 (1475 1150);
PAINT GREEN (1475 1150);
DISPLAY INVISIBLE (1475 1150);
FORCEADD DNS..1
(4725 1150);
PAINT RED (4725 1150);
FORCEPROP 2 LAST CDS_LIB mstr_misc
J 0
(4725 1150);
DISPLAY INVISIBLE (4725 1150);
FORCEPROP 1 LAST COMMENT_BODY TRUE
R 1
J 0
(4800 925);
DISPLAY 0.872340 (4800 925);
PAINT GREEN (4800 925);
DISPLAY INVISIBLE (4800 925);
FORCEADD DNS..1
(4725 1700);
PAINT RED (4725 1700);
FORCEPROP 2 LAST CDS_LIB mstr_misc
J 0
(4725 1700);
DISPLAY INVISIBLE (4725 1700);
FORCEPROP 1 LAST COMMENT_BODY TRUE
R 1
J 0
(4800 1475);
DISPLAY 0.872340 (4800 1475);
PAINT GREEN (4800 1475);
DISPLAY INVISIBLE (4800 1475);
FORCEADD DNS..1
(4825 3825);
PAINT RED (4825 3825);
FORCEPROP 2 LAST CDS_LIB mstr_misc
J 0
(4825 3825);
DISPLAY INVISIBLE (4825 3825);
FORCEPROP 1 LAST COMMENT_BODY TRUE
R 1
J 0
(4900 3600);
DISPLAY 0.872340 (4900 3600);
PAINT GREEN (4900 3600);
DISPLAY INVISIBLE (4900 3600);
FORCEADD DNS..1
(1425 4025);
PAINT RED (1425 4025);
FORCEPROP 2 LAST CDS_LIB mstr_misc
J 0
(1425 4025);
PAINT MONO (1425 4025);
DISPLAY INVISIBLE (1425 4025);
FORCEPROP 1 LAST COMMENT_BODY TRUE
R 1
J 0
(1500 3800);
DISPLAY 0.872340 (1500 3800);
PAINT GREEN (1500 3800);
DISPLAY INVISIBLE (1500 3800);
FORCEADD DNS..1
(4825 4350);
PAINT RED (4825 4350);
FORCEPROP 2 LAST CDS_LIB mstr_misc
J 0
(4825 4350);
DISPLAY INVISIBLE (4825 4350);
FORCEPROP 1 LAST COMMENT_BODY TRUE
R 1
J 0
(4900 4125);
DISPLAY 0.872340 (4900 4125);
PAINT GREEN (4900 4125);
DISPLAY INVISIBLE (4900 4125);
FORCEADD QUANTA_TITLE_BLOCK_C..1
(9400 100);
FORCEPROP 0 LAST CDS_CON_LAST_MODIFIED Fri Mar 11 14:53:29 2022
J 0
(7515 115);
DISPLAY INVISIBLE (7515 115);
FORCEPROP 1 LAST CUSTOM_TXT_CDS <CON_LAST_MODIFIED>
J 0
(7515 115);
DISPLAY 0.978723 (7515 115);
FORCEPROP 2 LAST CUSTOM_TXT_CDS <XR_PAGE_TITLE>
J 0
(1510 5350);
DISPLAY 0.638298 (1510 5350);
PAINT PINK (1510 5350);
DISPLAY INVISIBLE (1510 5350);
FORCEPROP 1 LAST CUSTOM_TXT_CDS <NAME_2>
J 0
(6225 150);
FORCEPROP 1 LAST CUSTOM_TXT_CDS <NAME_1>
J 0
(6225 275);
FORCEPROP 1 LAST CUSTOM_TXT_CDS <Q_NUMBER>
J 0
(7997 203);
DISPLAY 1.212766 (7997 203);
FORCEPROP 1 LAST CUSTOM_TXT_CDS <Q_PROJ>
J 0
(7018 202);
DISPLAY 1.212766 (7018 202);
FORCEPROP 1 LAST CUSTOM_TXT_CDS <Q_REV>
J 0
(9216 203);
DISPLAY 1.212766 (9216 203);
FORCEPROP 1 LAST CUSTOM_TXT_CDS <CON_PAGE_NUM> OF <CON_TOTAL_PAGES>
J 0
(8954 118);
DISPLAY 0.978723 (8954 118);
FORCEPROP 1 LAST Q_DEPT BU9
J 1
(5637 149);
DISPLAY 1.957447 (5637 149);
PAINT GREEN (5637 149);
FORCEPROP 1 LAST Q_TITLE PVDDCR_CPU1_P0 VR PHASE 5&6
J 0
(100 175);
DISPLAY 2.446809 (100 175);
PAINT GREEN (100 175);
FORCEPROP 1 LAST CDS_LMAN_SYM_OUTLINE -9475,6775,100,-125
J 0
(9400 100);
DISPLAY 0.468085 (9400 100);
PAINT GREEN (9400 100);
DISPLAY INVISIBLE (9400 100);
FORCEPROP 2 LAST CDS_LIB pure_quanta
J 0
(9400 100);
DISPLAY INVISIBLE (9400 100);
FORCEPROP 2 LAST PAGE_BORDER TRUE
J 0
(1510 5350);
DISPLAY 0.638298 (1510 5350);
PAINT PINK (1510 5350);
DISPLAY INVISIBLE (1510 5350);
FORCEPROP 1 LAST COMMENT_BODY TRUE
J 0
(9412 87);
DISPLAY 0.978723 (9412 87);
PAINT GREEN (9412 87);
DISPLAY INVISIBLE (9412 87);
FORCEPROP 2 LAST CDS_XR_PAGE_TITLE CR-179 : @T6G_MB_LIB.T6G(SCH_1):PAGE179
J 0
(1510 5350);
DISPLAY 0.638298 (1510 5350);
PAINT PINK (1510 5350);
DISPLAY INVISIBLE (1510 5350);
WIRE 16 -1 (2200 2800)(2200 2675);
WIRE 16 -1 (1850 2225)(1850 2175);
WIRE 16 -1 (1400 1300)(1400 1225);
WIRE 16 -1 (900 1375)(900 1425);
WIRE 16 -1 (4850 3725)(4850 3650);
WIRE 16 -1 (4750 1050)(4750 975);
WIRE 16 -1 (5175 1650)(5100 1650);
WIRE 16 -1 (5100 1650)(5100 1600);
WIRE 16 -1 (1425 3950)(1425 3875);
WIRE 16 -1 (1875 4875)(1875 4825);
WIRE 16 -1 (2225 5450)(2225 5325);
WIRE 16 -1 (925 4025)(925 4075);
WIRE 16 -1 (4675 2250)(5300 2250);
FORCEPROP 2 LAST SIG_NAME SW_PVDDCR_CPU1_P0_BOOT6_R
J 0
(4765 2260);
DISPLAY 0.489362 (4765 2260);
FORCEPROP 2 LASTPROP $XRERR UNIQUE?
J 0
(4525 2260);
DISPLAY 0.638298 (4525 2260);
PAINT MONO (4525 2260);
DISPLAY INVISIBLE (4525 2260);
WIRE 16 -1 (5300 2250)(5300 2225);
WIRE 16 -1 (4700 4900)(5325 4900);
FORCEPROP 2 LAST SIG_NAME SW_PVDDCR_CPU1_P0_BOOT5_R
J 0
(4790 4910);
DISPLAY 0.489362 (4790 4910);
FORCEPROP 2 LASTPROP $XRERR UNIQUE?
J 0
(4550 4910);
DISPLAY 0.638298 (4550 4910);
PAINT MONO (4550 4910);
DISPLAY INVISIBLE (4550 4910);
WIRE 16 -1 (5325 4900)(5325 4875);
WIRE 16 -1 (3750 4650)(5325 4650);
FORCEPROP 2 LAST SIG_NAME SW_PVDDCR_CPU1_P0_BOOTR5
J 0
(3940 4660);
DISPLAY 0.489362 (3940 4660);
FORCEPROP 2 LASTPROP $XRERR UNIQUE?
J 0
(3700 4660);
DISPLAY 0.638298 (3700 4660);
PAINT MONO (3700 4660);
DISPLAY INVISIBLE (3700 4660);
WIRE 16 -1 (5325 4650)(5325 4675);
WIRE 16 -1 (5800 5150)(5800 5200);
WIRE 16 -1 (5800 5350)(5800 5200);
WIRE 16 -1 (5425 5200)(5800 5200);
WIRE 16 -1 (5425 5350)(5425 5200);
WIRE 16 -1 (5025 5200)(5425 5200);
WIRE 16 -1 (5025 5350)(5025 5200);
WIRE 16 -1 (5025 5200)(4625 5200);
WIRE 16 -1 (4625 5350)(4625 5200);
WIRE 16 -1 (4200 5200)(4625 5200);
WIRE 16 -1 (4200 5350)(4200 5200);
WIRE 16 -1 (8075 4125)(7650 4125);
WIRE 16 -1 (8075 4050)(8075 4125);
WIRE 16 -1 (8075 4250)(8075 4125);
WIRE 16 -1 (7650 4125)(7650 4250);
WIRE 16 -1 (6650 4300)(7075 4300);
FORCEPROP 2 LAST SIG_NAME IND_CPU1_P0_CPL5
J 0
(6740 4310);
DISPLAY 0.489362 (6740 4310);
WIRE 16 -1 (5375 4300)(5850 4300);
FORCEPROP 2 LAST SIG_NAME IND_CPU1_P0_CPL6
J 0
(5415 4310);
DISPLAY 0.489362 (5415 4310);
WIRE 16 -1 (3750 4550)(4850 4550);
FORCEPROP 2 LAST SIG_NAME SW_PVDDCR_CPU1_P0_SW5
J 0
(3940 4560);
DISPLAY 0.489362 (3940 4560);
FORCEPROP 2 LASTPROP $XRERR UNIQUE?
J 0
(3700 4560);
DISPLAY 0.638298 (3700 4560);
PAINT MONO (3700 4560);
DISPLAY INVISIBLE (3700 4560);
WIRE 16 -1 (4850 4550)(5850 4550);
WIRE 16 -1 (4850 4450)(4850 4550);
WIRE 16 -1 (4850 4250)(4850 3925);
FORCEPROP 2 LAST SIG_NAME SW_PVDDCR_CPU1_P0_SW5_RC
J 0
(4890 4060);
DISPLAY 0.489362 (4890 4060);
FORCEPROP 2 LASTPROP $XRERR UNIQUE?
J 0
(4650 4060);
DISPLAY 0.638298 (4650 4060);
PAINT MONO (4650 4060);
DISPLAY INVISIBLE (4650 4060);
WIRE 16 -1 (8050 1475)(7625 1475);
WIRE 16 -1 (8050 1600)(8050 1475);
WIRE 16 -1 (8050 1400)(8050 1475);
WIRE 16 -1 (7625 1475)(7625 1600);
WIRE 16 -1 (7325 1900)(7325 775);
WIRE 16 -1 (7625 1900)(7325 1900);
WIRE 16 -1 (7325 1900)(6650 1900);
WIRE 16 -1 (7325 775)(6025 775);
WIRE 16 -1 (7625 1900)(8050 1900);
WIRE 16 -1 (7625 1900)(7625 1800);
WIRE 16 -1 (8050 1800)(8050 1900);
WIRE 16 -1 (8050 2000)(8050 1900);
WIRE 16 -1 (6650 1650)(7050 1650);
FORCEPROP 2 LAST SIG_NAME IND_CPU1_P0_CPL6
J 0
(6690 1660);
DISPLAY 0.489362 (6690 1660);
WIRE 16 -1 (3725 2250)(4475 2250);
FORCEPROP 2 LAST SIG_NAME SW_PVDDCR_CPU1_P0_BOOT6
J 0
(3940 2260);
DISPLAY 0.489362 (3940 2260);
FORCEPROP 2 LASTPROP $XRERR UNIQUE?
J 0
(3700 2260);
DISPLAY 0.638298 (3700 2260);
PAINT MONO (3700 2260);
DISPLAY INVISIBLE (3700 2260);
WIRE 16 -1 (3750 4900)(4500 4900);
FORCEPROP 2 LAST SIG_NAME SW_PVDDCR_CPU1_P0_BOOT5
J 0
(3965 4910);
DISPLAY 0.489362 (3965 4910);
FORCEPROP 2 LASTPROP $XRERR UNIQUE?
J 0
(3725 4910);
DISPLAY 0.638298 (3725 4910);
PAINT MONO (3725 4910);
DISPLAY INVISIBLE (3725 4910);
WIRE 16 -1 (3750 4250)(4350 4250);
FORCEPROP 2 LAST SIG_NAME NC_PVDDCR_CPU1_P0_GL1_5
J 0
(3865 4260);
DISPLAY 0.489362 (3865 4260);
FORCEPROP 2 LASTPROP $XRERR UNIQUE?
J 0
(4380 4250);
DISPLAY 0.638298 (4380 4250);
PAINT MONO (4380 4250);
DISPLAY INVISIBLE (4380 4250);
WIRE 16 -1 (3750 4200)(4350 4200);
FORCEPROP 2 LAST SIG_NAME NC_PVDDCR_CPU1_P0_GL2_5
J 0
(3865 4210);
DISPLAY 0.489362 (3865 4210);
FORCEPROP 2 LASTPROP $XRERR UNIQUE?
J 0
(4380 4200);
DISPLAY 0.638298 (4380 4200);
PAINT MONO (4380 4200);
DISPLAY INVISIBLE (4380 4200);
WIRE 16 -1 (3750 5150)(3925 5150);
WIRE 16 -1 (3925 5150)(3925 5200);
WIRE 16 -1 (3750 5200)(3925 5200);
WIRE 16 -1 (3925 5700)(3925 5200);
WIRE 16 -1 (4200 5700)(3925 5700);
WIRE 16 -1 (4625 5700)(4200 5700);
WIRE 16 -1 (4200 5550)(4200 5700);
WIRE 16 -1 (4625 5700)(5025 5700);
WIRE 16 -1 (4625 5550)(4625 5700);
WIRE 16 -1 (5025 5700)(5425 5700);
WIRE 16 -1 (5025 5700)(5025 5550);
WIRE 16 -1 (5425 5700)(5800 5700);
WIRE 16 -1 (5425 5550)(5425 5700);
WIRE 16 -1 (5800 5750)(5800 5700);
WIRE 16 -1 (5800 5550)(5800 5700);
WIRE 16 -1 (2900 4300)(2525 4300);
FORCEPROP 2 LAST SIG_NAME NC_PVDDCR_CPU1_P0_DNC5
J 0
(2330 4310);
DISPLAY 0.489362 (2330 4310);
FORCEPROP 2 LASTPROP $XRERR UNIQUE?
J 0
(2285 4300);
DISPLAY 0.638298 (2285 4300);
PAINT MONO (2285 4300);
DISPLAY INVISIBLE (2285 4300);
WIRE 16 -1 (2900 4550)(1950 4550);
FORCEPROP 2 LAST SIG_NAME PVDDCR_CPU1_P0_IMON5
J 0
(2065 4560);
DISPLAY 0.489362 (2065 4560);
WIRE 16 -1 (1875 5075)(1875 5175);
WIRE 16 -1 (1875 5175)(2200 5175);
WIRE 16 -1 (1875 5425)(1875 5175);
WIRE 16 -1 (2200 5175)(2200 4900);
WIRE 16 -1 (2800 4900)(2200 4900);
FORCEPROP 2 LAST SIG_NAME PVDDCR_CPU1_P0_VCC5
J 0
(2265 4910);
DISPLAY 0.489362 (2265 4910);
FORCEPROP 2 LASTPROP $XRERR UNIQUE?
J 0
(2025 4910);
DISPLAY 0.638298 (2025 4910);
PAINT MONO (2025 4910);
DISPLAY INVISIBLE (2025 4910);
WIRE 16 -1 (2800 4900)(2900 4900);
WIRE 16 -1 (2800 4700)(2800 4900);
WIRE 16 -1 (2900 4700)(2800 4700);
WIRE 16 -1 (1875 5625)(1875 5750);
WIRE 16 -1 (2225 5750)(1875 5750);
WIRE 16 -1 (1875 5900)(1875 5750);
WIRE 16 -1 (2225 5650)(2225 5750);
WIRE 16 -1 (2550 5750)(2225 5750);
WIRE 16 -1 (2550 5200)(2550 5750);
WIRE 16 -1 (2900 5200)(2550 5200);
WIRE 16 -1 (2800 4375)(925 4375);
WIRE 16 -1 (2800 4450)(2800 4375);
FORCEPROP 0 LAST CDS_PHYS_NET_NAME PVCCIN_CPU0_VREF
J 0
(2800 4400);
PAINT MONO (2800 4400);
DISPLAY INVISIBLE (2800 4400);
WIRE 16 -1 (925 4375)(925 4275);
WIRE 16 -1 (1950 4450)(2800 4450);
FORCEPROP 2 LAST SIG_NAME PVDDCR_CPU1_P0_VCCS
J 0
(2065 4460);
DISPLAY 0.489362 (2065 4460);
WIRE 16 -1 (2800 4450)(2900 4450);
WIRE 16 -1 (1425 4250)(2900 4250);
FORCEPROP 2 LAST SIG_NAME PVDDCR_CPU1_P0_LSET5
J 0
(1940 4260);
DISPLAY 0.489362 (1940 4260);
FORCEPROP 2 LASTPROP $XRERR UNIQUE?
J 0
(1700 4260);
DISPLAY 0.638298 (1700 4260);
PAINT MONO (1700 4260);
DISPLAY INVISIBLE (1700 4260);
WIRE 16 -1 (1425 4250)(1425 4150);
WIRE 16 -1 (2875 1650)(2500 1650);
FORCEPROP 2 LAST SIG_NAME NC_PVDDCR_CPU1_P0_DNC6
J 0
(2305 1660);
DISPLAY 0.489362 (2305 1660);
FORCEPROP 2 LASTPROP $XRERR UNIQUE?
J 0
(2260 1650);
DISPLAY 0.638298 (2260 1650);
PAINT MONO (2260 1650);
DISPLAY INVISIBLE (2260 1650);
WIRE 16 -1 (2900 4050)(1950 4050);
FORCEPROP 2 LAST SIG_NAME PVDDCR_CPU1_P0_TEMP0
J 0
(2065 4060);
DISPLAY 0.489362 (2065 4060);
WIRE 16 -1 (2900 3950)(1950 3950);
FORCEPROP 2 LAST SIG_NAME PVDDCR_CPU1_P0_PWM5
J 0
(2065 3960);
DISPLAY 0.489362 (2065 3960);
WIRE 16 -1 (2875 1900)(1925 1900);
FORCEPROP 2 LAST SIG_NAME PVDDCR_CPU1_P0_IMON6
J 0
(2040 1910);
DISPLAY 0.489362 (2040 1910);
WIRE 16 -1 (1850 2975)(1850 3100);
WIRE 16 -1 (2200 3100)(1850 3100);
WIRE 16 -1 (1850 3250)(1850 3100);
WIRE 16 -1 (2525 3100)(2200 3100);
WIRE 16 -1 (2200 3000)(2200 3100);
WIRE 16 -1 (2525 2550)(2525 3100);
WIRE 16 -1 (2875 2550)(2525 2550);
WIRE 16 -1 (2775 1725)(900 1725);
WIRE 16 -1 (2775 1800)(2775 1725);
FORCEPROP 0 LAST CDS_PHYS_NET_NAME PVCCIN_CPU0_VREF
J 0
(2775 1750);
PAINT MONO (2775 1750);
DISPLAY INVISIBLE (2775 1750);
WIRE 16 -1 (900 1725)(900 1625);
WIRE 16 -1 (1925 1800)(2775 1800);
FORCEPROP 2 LAST SIG_NAME PVDDCR_CPU1_P0_VCCS
J 0
(2040 1810);
DISPLAY 0.489362 (2040 1810);
WIRE 16 -1 (2775 1800)(2875 1800);
WIRE 16 -1 (1850 2425)(1850 2525);
WIRE 16 -1 (1850 2525)(2175 2525);
WIRE 16 -1 (1850 2775)(1850 2525);
WIRE 16 -1 (2175 2525)(2175 2250);
WIRE 16 -1 (2775 2250)(2175 2250);
FORCEPROP 2 LAST SIG_NAME PVDDCR_CPU1_P0_VCC6
J 0
(2240 2260);
DISPLAY 0.489362 (2240 2260);
FORCEPROP 2 LASTPROP $XRERR UNIQUE?
J 0
(2000 2260);
DISPLAY 0.638298 (2000 2260);
PAINT MONO (2000 2260);
DISPLAY INVISIBLE (2000 2260);
WIRE 16 -1 (2775 2250)(2875 2250);
WIRE 16 -1 (2775 2050)(2775 2250);
WIRE 16 -1 (2875 2050)(2775 2050);
WIRE 16 -1 (3750 4100)(4000 4100);
WIRE 16 -1 (4000 4100)(4000 4050);
WIRE 16 -1 (3750 4050)(4000 4050);
WIRE 16 -1 (4000 4050)(4000 4000);
WIRE 16 -1 (4000 4000)(4000 3950);
WIRE 16 -1 (3750 4000)(4000 4000);
WIRE 16 -1 (4000 3950)(4000 3875);
WIRE 16 -1 (3750 3950)(4000 3950);
WIRE 16 -1 (7350 4550)(7350 3475);
WIRE 16 -1 (7650 4550)(7350 4550);
WIRE 16 -1 (7350 4550)(6650 4550);
WIRE 16 -1 (7350 3475)(6100 3475);
WIRE 16 -1 (7650 4550)(8075 4550);
WIRE 16 -1 (7650 4550)(7650 4450);
WIRE 16 -1 (8075 4650)(8075 4550);
WIRE 16 -1 (8075 4450)(8075 4550);
WIRE 16 -1 (3725 1450)(3975 1450);
WIRE 16 -1 (3975 1450)(3975 1400);
WIRE 16 -1 (3725 1400)(3975 1400);
WIRE 16 -1 (3975 1400)(3975 1350);
WIRE 16 -1 (3975 1350)(3975 1300);
WIRE 16 -1 (3725 1350)(3975 1350);
WIRE 16 -1 (3975 1300)(3975 1225);
WIRE 16 -1 (3725 1300)(3975 1300);
WIRE 16 -1 (3725 2000)(5300 2000);
FORCEPROP 2 LAST SIG_NAME SW_PVDDCR_CPU1_P0_BOOTR6
J 0
(3915 2010);
DISPLAY 0.489362 (3915 2010);
FORCEPROP 2 LASTPROP $XRERR UNIQUE?
J 0
(3675 2010);
DISPLAY 0.638298 (3675 2010);
PAINT MONO (3675 2010);
DISPLAY INVISIBLE (3675 2010);
WIRE 16 -1 (5300 2000)(5300 2025);
WIRE 16 -1 (5375 1650)(5850 1650);
WIRE 16 -1 (5900 3475)(4575 3475);
FORCEPROP 2 LAST SIG_NAME PVDDCR_CPU1_P0_VOS5
J 0
(3865 4325);
DISPLAY 0.489362 (3865 4325);
FORCEPROP 2 LASTPROP $XRERR UNIQUE?
J 0
(3625 4325);
DISPLAY 0.638298 (3625 4325);
PAINT MONO (3625 4325);
DISPLAY INVISIBLE (3625 4325);
WIRE 16 -1 (4575 4300)(4575 3475);
WIRE 16 -1 (3750 4300)(4575 4300);
WIRE 16 -1 (5775 2900)(5775 3050);
WIRE 16 -1 (5775 3100)(5775 3050);
WIRE 16 -1 (5400 3050)(5775 3050);
WIRE 16 -1 (5400 2900)(5400 3050);
WIRE 16 -1 (5000 3050)(5400 3050);
WIRE 16 -1 (5000 3050)(5000 2900);
WIRE 16 -1 (4600 3050)(5000 3050);
WIRE 16 -1 (4600 2900)(4600 3050);
WIRE 16 -1 (4600 3050)(4175 3050);
WIRE 16 -1 (4175 2900)(4175 3050);
WIRE 16 -1 (4175 3050)(3900 3050);
WIRE 16 -1 (3900 3050)(3900 2550);
WIRE 16 -1 (3725 2550)(3900 2550);
WIRE 16 -1 (3900 2500)(3900 2550);
WIRE 16 -1 (3725 2500)(3900 2500);
WIRE 16 -1 (5775 2500)(5775 2550);
WIRE 16 -1 (5775 2700)(5775 2550);
WIRE 16 -1 (5400 2550)(5775 2550);
WIRE 16 -1 (5400 2700)(5400 2550);
WIRE 16 -1 (5000 2550)(5400 2550);
WIRE 16 -1 (5000 2700)(5000 2550);
WIRE 16 -1 (5000 2550)(4600 2550);
WIRE 16 -1 (4600 2700)(4600 2550);
WIRE 16 -1 (4175 2550)(4600 2550);
WIRE 16 -1 (4175 2700)(4175 2550);
WIRE 16 -1 (3725 1900)(4750 1900);
FORCEPROP 2 LAST SIG_NAME SW_PVDDCR_CPU1_P0_SW6
J 0
(3915 1910);
DISPLAY 0.489362 (3915 1910);
FORCEPROP 2 LASTPROP $XRERR UNIQUE?
J 0
(3675 1910);
DISPLAY 0.638298 (3675 1910);
PAINT MONO (3675 1910);
DISPLAY INVISIBLE (3675 1910);
WIRE 16 -1 (4750 1900)(5850 1900);
WIRE 16 -1 (4750 1800)(4750 1900);
WIRE 16 -1 (3725 1600)(4325 1600);
FORCEPROP 2 LAST SIG_NAME NC_PVDDCR_CPU1_P0_GL1_6
J 0
(3840 1610);
DISPLAY 0.489362 (3840 1610);
FORCEPROP 2 LASTPROP $XRERR UNIQUE?
J 0
(4355 1600);
DISPLAY 0.638298 (4355 1600);
PAINT MONO (4355 1600);
DISPLAY INVISIBLE (4355 1600);
WIRE 16 -1 (3725 1550)(4325 1550);
FORCEPROP 2 LAST SIG_NAME NC_PVDDCR_CPU1_P0_GL2_6
J 0
(3840 1560);
DISPLAY 0.489362 (3840 1560);
FORCEPROP 2 LASTPROP $XRERR UNIQUE?
J 0
(4355 1550);
DISPLAY 0.638298 (4355 1550);
PAINT MONO (4355 1550);
DISPLAY INVISIBLE (4355 1550);
WIRE 16 -1 (4750 1600)(4750 1250);
FORCEPROP 2 LAST SIG_NAME SW_PVDDCR_CPU1_P0_SW6_RC
J 0
(4790 1325);
DISPLAY 0.489362 (4790 1325);
FORCEPROP 2 LASTPROP $XRERR UNIQUE?
J 0
(4550 1325);
DISPLAY 0.638298 (4550 1325);
PAINT MONO (4550 1325);
DISPLAY INVISIBLE (4550 1325);
WIRE 16 -1 (1400 1600)(2875 1600);
FORCEPROP 2 LAST SIG_NAME PVDDCR_CPU1_P0_LSET6
J 0
(1915 1610);
DISPLAY 0.489362 (1915 1610);
FORCEPROP 2 LASTPROP $XRERR UNIQUE?
J 0
(1675 1610);
DISPLAY 0.638298 (1675 1610);
PAINT MONO (1675 1610);
DISPLAY INVISIBLE (1675 1610);
WIRE 16 -1 (1400 1600)(1400 1500);
WIRE 16 -1 (2875 1400)(1925 1400);
FORCEPROP 2 LAST SIG_NAME PVDDCR_CPU1_P0_TEMP0
J 0
(2040 1410);
DISPLAY 0.489362 (2040 1410);
WIRE 16 -1 (2875 1300)(1925 1300);
FORCEPROP 2 LAST SIG_NAME PVDDCR_CPU1_P0_PWM6
J 0
(2040 1310);
DISPLAY 0.489362 (2040 1310);
WIRE 16 -1 (5825 775)(4550 775);
FORCEPROP 2 LAST SIG_NAME PVDDCR_CPU1_P0_VOS6
J 0
(3840 1675);
DISPLAY 0.489362 (3840 1675);
FORCEPROP 2 LASTPROP $XRERR UNIQUE?
J 0
(3600 1675);
DISPLAY 0.638298 (3600 1675);
PAINT MONO (3600 1675);
DISPLAY INVISIBLE (3600 1675);
WIRE 16 -1 (4550 1650)(4550 775);
WIRE 16 -1 (3725 1650)(4550 1650);
DOT 1 (1850 3100);
DOT 1 (2200 3100);
DOT 1 (1875 5750);
DOT 1 (5775 2550);
DOT 1 (4000 4050);
DOT 1 (5000 3050);
DOT 1 (8050 1900);
DOT 1 (8050 1475);
DOT 1 (7625 1900);
DOT 1 (7325 1900);
DOT 1 (5775 3050);
DOT 1 (4600 3050);
DOT 1 (4600 2550);
DOT 1 (2775 2250);
DOT 1 (2775 1800);
DOT 1 (1850 2525);
DOT 1 (3975 1350);
DOT 1 (3975 1300);
DOT 1 (3900 2550);
DOT 1 (4000 4000);
DOT 1 (1875 5175);
DOT 1 (2800 4450);
DOT 1 (2800 4900);
DOT 1 (2225 5750);
DOT 1 (3925 5200);
DOT 1 (4200 5700);
DOT 1 (5025 5200);
DOT 1 (4625 5700);
DOT 1 (5025 5700);
DOT 1 (5425 5200);
DOT 1 (5425 5700);
DOT 1 (5800 5200);
DOT 1 (5800 5700);
DOT 1 (7350 4550);
DOT 1 (7650 4550);
DOT 1 (8075 4125);
DOT 1 (8075 4550);
DOT 1 (5400 2550);
DOT 1 (4625 5200);
DOT 1 (5400 3050);
DOT 1 (4850 4550);
DOT 1 (4750 1900);
DOT 1 (4000 3950);
DOT 1 (4175 3050);
DOT 1 (5000 2550);
DOT 1 (3975 1400);
FORCENOTE
PVDDCR_CPU1_P0_PHASE5
(2975 5725) 0;
DISPLAY LEFT (2975 5725);
DISPLAY 1.021277 (2975 5725);
PAINT WHITE (2975 5725);
FORCENOTE
PGL6303.151HLT
(6700 4875) 0;
DISPLAY LEFT (6700 4875);
DISPLAY 0.638298 (6700 4875);
PAINT WHITE (6700 4875);
FORCENOTE
ISAT:70A@100C
(6700 4825) 0;
DISPLAY LEFT (6700 4825);
DISPLAY 0.638298 (6700 4825);
PAINT WHITE (6700 4825);
FORCENOTE
DCR=1-4,0.105M OHM
(6700 2075) 0;
DISPLAY LEFT (6700 2075);
DISPLAY 0.638298 (6700 2075);
PAINT WHITE (6700 2075);
FORCENOTE
11.0*7.5*12.5
(6700 2125) 0;
DISPLAY LEFT (6700 2125);
DISPLAY 0.638298 (6700 2125);
PAINT WHITE (6700 2125);
FORCENOTE
ISAT:70A@100C
(6700 2175) 0;
DISPLAY LEFT (6700 2175);
DISPLAY 0.638298 (6700 2175);
PAINT WHITE (6700 2175);
FORCENOTE
PGL6303.151HLT
(6700 2225) 0;
DISPLAY LEFT (6700 2225);
DISPLAY 0.638298 (6700 2225);
PAINT WHITE (6700 2225);
FORCENOTE
PVDDCR_CPU1_P0_PHASE6
(2950 3075) 0;
DISPLAY LEFT (2950 3075);
DISPLAY 1.021277 (2950 3075);
PAINT WHITE (2950 3075);
FORCENOTE
DCR=2-3,0.27M OHM
(6700 2025) 0;
DISPLAY LEFT (6700 2025);
DISPLAY 0.638298 (6700 2025);
PAINT WHITE (6700 2025);
FORCENOTE
2ND=CV+15^0TZ01
(6700 1975) 0;
DISPLAY LEFT (6700 1975);
DISPLAY 0.638298 (6700 1975);
PAINT WHITE (6700 1975);
FORCENOTE
11.0*7.5*12.5
(6700 4775) 0;
DISPLAY LEFT (6700 4775);
DISPLAY 0.638298 (6700 4775);
PAINT WHITE (6700 4775);
FORCENOTE
DCR=1-4,0.105M OHM
(6700 4725) 0;
DISPLAY LEFT (6700 4725);
DISPLAY 0.638298 (6700 4725);
PAINT WHITE (6700 4725);
FORCENOTE
DCR=2-3,0.27M OHM
(6700 4675) 0;
DISPLAY LEFT (6700 4675);
DISPLAY 0.638298 (6700 4675);
PAINT WHITE (6700 4675);
FORCENOTE
2ND=CV+15^0TZ01
(6700 4625) 0;
DISPLAY LEFT (6700 4625);
DISPLAY 0.638298 (6700 4625);
PAINT WHITE (6700 4625);
FORCENOTE
2ND=CV+22Y0EZ01
(5175 1400) 0;
DISPLAY LEFT (5175 1400);
DISPLAY 0.638298 (5175 1400);
PAINT WHITE (5175 1400);
FORCENOTE
HCME656510Q-221QL
(5175 1600) 0;
DISPLAY LEFT (5175 1600);
DISPLAY 0.638298 (5175 1600);
PAINT WHITE (5175 1600);
FORCENOTE
ISAT:30A@100C
(5175 1550) 0;
DISPLAY LEFT (5175 1550);
DISPLAY 0.638298 (5175 1550);
PAINT WHITE (5175 1550);
FORCENOTE
6.5*6.5*10.0
(5175 1500) 0;
DISPLAY LEFT (5175 1500);
DISPLAY 0.638298 (5175 1500);
PAINT WHITE (5175 1500);
FORCENOTE
DCR=0.17M OHM
(5175 1450) 0;
DISPLAY LEFT (5175 1450);
DISPLAY 0.638298 (5175 1450);
PAINT WHITE (5175 1450);
QUIT
